FILE_TYPE = MACRO_DRAWING;
SET COLOR_WIRE YELLOW;
SET COLOR_PROP ORANGE;
SET COLOR_DOT WHITE;
SET COLOR_ARC YELLOW;
SET COLOR_BODY GREEN;
SET COLOR_NOTE PURPLE;
SET PROP_DISPLAY VALUE;
SET PAGE_NUMBER P17;
FORCEADD GENOA_SP5..8
(-4600 3600);
FORCEPROP 1 LAST LOCATION U25
J 0
(-5245 6431);
DISPLAY 0.489362 (-5245 6431);
PAINT SKYBLUE (-5245 6431);
FORCEPROP 0 LAST $SEC 8
J 0
(-5225 6475);
DISPLAY 0.680851 (-5225 6475);
PAINT MONO (-5225 6475);
DISPLAY INVISIBLE (-5225 6475);
FORCEPROP 0 LAST CDS_SEC 8
J 0
(-5250 6400);
DISPLAY 1.021277 (-5250 6400);
DISPLAY INVISIBLE (-5250 6400);
FORCEPROP 0 LASTPIN (-5400 2975) $PN BC12
J 2
(-5410 2985);
DISPLAY 0.489362 (-5410 2985);
PAINT MONO (-5410 2985);
FORCEPROP 0 LASTPIN (-5400 2925) $PN BD13
J 2
(-5410 2935);
DISPLAY 0.489362 (-5410 2935);
PAINT MONO (-5410 2935);
FORCEPROP 0 LASTPIN (-5400 1825) $PN BF13
J 2
(-5410 1835);
DISPLAY 0.489362 (-5410 1835);
PAINT MONO (-5410 1835);
FORCEPROP 0 LASTPIN (-5400 1775) $PN BG12
J 2
(-5410 1785);
DISPLAY 0.489362 (-5410 1785);
PAINT MONO (-5410 1785);
FORCEPROP 0 LASTPIN (-5400 2125) $PN AT14
J 2
(-5410 2135);
DISPLAY 0.489362 (-5410 2135);
PAINT MONO (-5410 2135);
FORCEPROP 0 LASTPIN (-5400 2025) $PN AU14
J 2
(-5410 2035);
DISPLAY 0.489362 (-5410 2035);
PAINT MONO (-5410 2035);
FORCEPROP 0 LASTPIN (-5400 2825) $PN AU12
J 2
(-5410 2835);
DISPLAY 0.489362 (-5410 2835);
PAINT MONO (-5410 2835);
FORCEPROP 0 LASTPIN (-5400 2775) $PN AV14
J 2
(-5410 2785);
DISPLAY 0.489362 (-5410 2785);
PAINT MONO (-5410 2785);
FORCEPROP 0 LASTPIN (-5400 2675) $PN BN14
J 2
(-5410 2685);
DISPLAY 0.489362 (-5410 2685);
PAINT MONO (-5410 2685);
FORCEPROP 0 LASTPIN (-5400 1675) $PN AV13
J 2
(-5410 1685);
DISPLAY 0.489362 (-5410 1685);
PAINT MONO (-5410 1685);
FORCEPROP 0 LASTPIN (-5400 1625) $PN AW14
J 2
(-5410 1635);
DISPLAY 0.489362 (-5410 1635);
PAINT MONO (-5410 1635);
FORCEPROP 0 LASTPIN (-5400 1525) $PN BP14
J 2
(-5410 1535);
DISPLAY 0.489362 (-5410 1535);
PAINT MONO (-5410 1535);
FORCEPROP 0 LASTPIN (-5400 3825) $PN AW12
J 2
(-5410 3835);
DISPLAY 0.489362 (-5410 3835);
PAINT MONO (-5410 3835);
FORCEPROP 0 LASTPIN (-5400 3775) $PN AY13
J 2
(-5410 3785);
DISPLAY 0.489362 (-5410 3785);
PAINT MONO (-5410 3785);
FORCEPROP 0 LASTPIN (-5400 3725) $PN AY14
J 2
(-5410 3735);
DISPLAY 0.489362 (-5410 3735);
PAINT MONO (-5410 3735);
FORCEPROP 0 LASTPIN (-5400 3675) $PN BA14
J 2
(-5410 3685);
DISPLAY 0.489362 (-5410 3685);
PAINT MONO (-5410 3685);
FORCEPROP 0 LASTPIN (-5400 3625) $PN BA12
J 2
(-5410 3635);
DISPLAY 0.489362 (-5410 3635);
PAINT MONO (-5410 3635);
FORCEPROP 0 LASTPIN (-5400 3575) $PN BB13
J 2
(-5410 3585);
DISPLAY 0.489362 (-5410 3585);
PAINT MONO (-5410 3585);
FORCEPROP 0 LASTPIN (-5400 3525) $PN BB14
J 2
(-5410 3535);
DISPLAY 0.489362 (-5410 3535);
PAINT MONO (-5410 3535);
FORCEPROP 0 LASTPIN (-3800 2375) $PN AJ12
J 0
(-3790 2385);
DISPLAY 0.489362 (-3790 2385);
PAINT MONO (-3790 2385);
FORCEPROP 0 LASTPIN (-3800 2325) $PN AK14
J 0
(-3790 2335);
DISPLAY 0.489362 (-3790 2335);
PAINT MONO (-3790 2335);
FORCEPROP 0 LASTPIN (-3800 2275) $PN AK13
J 0
(-3790 2285);
DISPLAY 0.489362 (-3790 2285);
PAINT MONO (-3790 2285);
FORCEPROP 0 LASTPIN (-3800 2225) $PN AL14
J 0
(-3790 2235);
DISPLAY 0.489362 (-3790 2235);
PAINT MONO (-3790 2235);
FORCEPROP 0 LASTPIN (-3800 2175) $PN AN12
J 0
(-3790 2185);
DISPLAY 0.489362 (-3790 2185);
PAINT MONO (-3790 2185);
FORCEPROP 0 LASTPIN (-3800 2125) $PN AP14
J 0
(-3790 2135);
DISPLAY 0.489362 (-3790 2135);
PAINT MONO (-3790 2135);
FORCEPROP 0 LASTPIN (-3800 2075) $PN AP13
J 0
(-3790 2085);
DISPLAY 0.489362 (-3790 2085);
PAINT MONO (-3790 2085);
FORCEPROP 0 LASTPIN (-3800 2025) $PN AR14
J 0
(-3790 2035);
DISPLAY 0.489362 (-3790 2035);
PAINT MONO (-3790 2035);
FORCEPROP 0 LASTPIN (-3800 5975) $PN E12
J 0
(-3790 5985);
DISPLAY 0.489362 (-3790 5985);
PAINT MONO (-3790 5985);
FORCEPROP 0 LASTPIN (-3800 5925) $PN F14
J 0
(-3790 5935);
DISPLAY 0.489362 (-3790 5935);
PAINT MONO (-3790 5935);
FORCEPROP 0 LASTPIN (-3800 5875) $PN F13
J 0
(-3790 5885);
DISPLAY 0.489362 (-3790 5885);
PAINT MONO (-3790 5885);
FORCEPROP 0 LASTPIN (-3800 5825) $PN G14
J 0
(-3790 5835);
DISPLAY 0.489362 (-3790 5835);
PAINT MONO (-3790 5835);
FORCEPROP 0 LASTPIN (-3800 5775) $PN J12
J 0
(-3790 5785);
DISPLAY 0.489362 (-3790 5785);
PAINT MONO (-3790 5785);
FORCEPROP 0 LASTPIN (-3800 5725) $PN K14
J 0
(-3790 5735);
DISPLAY 0.489362 (-3790 5735);
PAINT MONO (-3790 5735);
FORCEPROP 0 LASTPIN (-3800 5675) $PN K13
J 0
(-3790 5685);
DISPLAY 0.489362 (-3790 5685);
PAINT MONO (-3790 5685);
FORCEPROP 0 LASTPIN (-3800 5625) $PN L14
J 0
(-3790 5635);
DISPLAY 0.489362 (-3790 5635);
PAINT MONO (-3790 5635);
FORCEPROP 0 LASTPIN (-3800 5525) $PN L12
J 0
(-3790 5535);
DISPLAY 0.489362 (-3790 5535);
PAINT MONO (-3790 5535);
FORCEPROP 0 LASTPIN (-3800 5475) $PN M14
J 0
(-3790 5485);
DISPLAY 0.489362 (-3790 5485);
PAINT MONO (-3790 5485);
FORCEPROP 0 LASTPIN (-3800 5425) $PN M13
J 0
(-3790 5435);
DISPLAY 0.489362 (-3790 5435);
PAINT MONO (-3790 5435);
FORCEPROP 0 LASTPIN (-3800 5375) $PN N14
J 0
(-3790 5385);
DISPLAY 0.489362 (-3790 5385);
PAINT MONO (-3790 5385);
FORCEPROP 0 LASTPIN (-3800 5325) $PN R12
J 0
(-3790 5335);
DISPLAY 0.489362 (-3790 5335);
PAINT MONO (-3790 5335);
FORCEPROP 0 LASTPIN (-3800 5275) $PN T14
J 0
(-3790 5285);
DISPLAY 0.489362 (-3790 5285);
PAINT MONO (-3790 5285);
FORCEPROP 0 LASTPIN (-3800 5225) $PN T13
J 0
(-3790 5235);
DISPLAY 0.489362 (-3790 5235);
PAINT MONO (-3790 5235);
FORCEPROP 0 LASTPIN (-3800 5175) $PN U14
J 0
(-3790 5185);
DISPLAY 0.489362 (-3790 5185);
PAINT MONO (-3790 5185);
FORCEPROP 0 LASTPIN (-3800 5075) $PN U12
J 0
(-3790 5085);
DISPLAY 0.489362 (-3790 5085);
PAINT MONO (-3790 5085);
FORCEPROP 0 LASTPIN (-3800 5025) $PN V14
J 0
(-3790 5035);
DISPLAY 0.489362 (-3790 5035);
PAINT MONO (-3790 5035);
FORCEPROP 0 LASTPIN (-3800 4975) $PN V13
J 0
(-3790 4985);
DISPLAY 0.489362 (-3790 4985);
PAINT MONO (-3790 4985);
FORCEPROP 0 LASTPIN (-3800 4925) $PN W14
J 0
(-3790 4935);
DISPLAY 0.489362 (-3790 4935);
PAINT MONO (-3790 4935);
FORCEPROP 0 LASTPIN (-3800 4875) $PN AA12
J 0
(-3790 4885);
DISPLAY 0.489362 (-3790 4885);
PAINT MONO (-3790 4885);
FORCEPROP 0 LASTPIN (-3800 4825) $PN AB14
J 0
(-3790 4835);
DISPLAY 0.489362 (-3790 4835);
PAINT MONO (-3790 4835);
FORCEPROP 0 LASTPIN (-3800 4775) $PN AB13
J 0
(-3790 4785);
DISPLAY 0.489362 (-3790 4785);
PAINT MONO (-3790 4785);
FORCEPROP 0 LASTPIN (-3800 4725) $PN AC14
J 0
(-3790 4735);
DISPLAY 0.489362 (-3790 4735);
PAINT MONO (-3790 4735);
FORCEPROP 0 LASTPIN (-3800 4625) $PN AC12
J 0
(-3790 4635);
DISPLAY 0.489362 (-3790 4635);
PAINT MONO (-3790 4635);
FORCEPROP 0 LASTPIN (-3800 4575) $PN AD14
J 0
(-3790 4585);
DISPLAY 0.489362 (-3790 4585);
PAINT MONO (-3790 4585);
FORCEPROP 0 LASTPIN (-3800 4525) $PN AD13
J 0
(-3790 4535);
DISPLAY 0.489362 (-3790 4535);
PAINT MONO (-3790 4535);
FORCEPROP 0 LASTPIN (-3800 4475) $PN AE14
J 0
(-3790 4485);
DISPLAY 0.489362 (-3790 4485);
PAINT MONO (-3790 4485);
FORCEPROP 0 LASTPIN (-3800 4425) $PN AG12
J 0
(-3790 4435);
DISPLAY 0.489362 (-3790 4435);
PAINT MONO (-3790 4435);
FORCEPROP 0 LASTPIN (-3800 4375) $PN AH14
J 0
(-3790 4385);
DISPLAY 0.489362 (-3790 4385);
PAINT MONO (-3790 4385);
FORCEPROP 0 LASTPIN (-3800 4325) $PN AH13
J 0
(-3790 4335);
DISPLAY 0.489362 (-3790 4335);
PAINT MONO (-3790 4335);
FORCEPROP 0 LASTPIN (-3800 4275) $PN AJ14
J 0
(-3790 4285);
DISPLAY 0.489362 (-3790 4285);
PAINT MONO (-3790 4285);
FORCEPROP 0 LASTPIN (-5400 5975) $PN G12
J 2
(-5410 5985);
DISPLAY 0.489362 (-5410 5985);
PAINT MONO (-5410 5985);
FORCEPROP 0 LASTPIN (-5400 5875) $PN N12
J 2
(-5410 5885);
DISPLAY 0.489362 (-5410 5885);
PAINT MONO (-5410 5885);
FORCEPROP 0 LASTPIN (-5400 5775) $PN W12
J 2
(-5410 5785);
DISPLAY 0.489362 (-5410 5785);
PAINT MONO (-5410 5785);
FORCEPROP 0 LASTPIN (-5400 5675) $PN AE12
J 2
(-5410 5685);
DISPLAY 0.489362 (-5410 5685);
PAINT MONO (-5410 5685);
FORCEPROP 0 LASTPIN (-5400 5575) $PN AL12
J 2
(-5410 5585);
DISPLAY 0.489362 (-5410 5585);
PAINT MONO (-5410 5585);
FORCEPROP 0 LASTPIN (-5400 5475) $PN J14
J 2
(-5410 5485);
DISPLAY 0.489362 (-5410 5485);
PAINT MONO (-5410 5485);
FORCEPROP 0 LASTPIN (-5400 5375) $PN R14
J 2
(-5410 5385);
DISPLAY 0.489362 (-5410 5385);
PAINT MONO (-5410 5385);
FORCEPROP 0 LASTPIN (-5400 5275) $PN AA14
J 2
(-5410 5285);
DISPLAY 0.489362 (-5410 5285);
PAINT MONO (-5410 5285);
FORCEPROP 0 LASTPIN (-5400 5175) $PN AG14
J 2
(-5410 5185);
DISPLAY 0.489362 (-5410 5185);
PAINT MONO (-5410 5185);
FORCEPROP 0 LASTPIN (-5400 5075) $PN AN14
J 2
(-5410 5085);
DISPLAY 0.489362 (-5410 5085);
PAINT MONO (-5410 5085);
FORCEPROP 0 LASTPIN (-5400 5925) $PN H13
J 2
(-5410 5935);
DISPLAY 0.489362 (-5410 5935);
PAINT MONO (-5410 5935);
FORCEPROP 0 LASTPIN (-5400 5825) $PN P13
J 2
(-5410 5835);
DISPLAY 0.489362 (-5410 5835);
PAINT MONO (-5410 5835);
FORCEPROP 0 LASTPIN (-5400 5725) $PN Y13
J 2
(-5410 5735);
DISPLAY 0.489362 (-5410 5735);
PAINT MONO (-5410 5735);
FORCEPROP 0 LASTPIN (-5400 5625) $PN AF13
J 2
(-5410 5635);
DISPLAY 0.489362 (-5410 5635);
PAINT MONO (-5410 5635);
FORCEPROP 0 LASTPIN (-5400 5525) $PN AM13
J 2
(-5410 5535);
DISPLAY 0.489362 (-5410 5535);
PAINT MONO (-5410 5535);
FORCEPROP 0 LASTPIN (-5400 5425) $PN H14
J 2
(-5410 5435);
DISPLAY 0.489362 (-5410 5435);
PAINT MONO (-5410 5435);
FORCEPROP 0 LASTPIN (-5400 5325) $PN P14
J 2
(-5410 5335);
DISPLAY 0.489362 (-5410 5335);
PAINT MONO (-5410 5335);
FORCEPROP 0 LASTPIN (-5400 5225) $PN Y14
J 2
(-5410 5235);
DISPLAY 0.489362 (-5410 5235);
PAINT MONO (-5410 5235);
FORCEPROP 0 LASTPIN (-5400 5125) $PN AF14
J 2
(-5410 5135);
DISPLAY 0.489362 (-5410 5135);
PAINT MONO (-5410 5135);
FORCEPROP 0 LASTPIN (-5400 5025) $PN AM14
J 2
(-5410 5035);
DISPLAY 0.489362 (-5410 5035);
PAINT MONO (-5410 5035);
FORCEPROP 0 LASTPIN (-5400 2575) $PN BC14
J 2
(-5410 2585);
DISPLAY 0.489362 (-5410 2585);
PAINT MONO (-5410 2585);
FORCEPROP 0 LASTPIN (-5400 2475) $PN BM14
J 2
(-5410 2485);
DISPLAY 0.489362 (-5410 2485);
PAINT MONO (-5410 2485);
FORCEPROP 0 LASTPIN (-5400 2425) $PN BN12
J 2
(-5410 2435);
DISPLAY 0.489362 (-5410 2435);
PAINT MONO (-5410 2435);
FORCEPROP 0 LASTPIN (-5400 2325) $PN BP13
J 2
(-5410 2335);
DISPLAY 0.489362 (-5410 2335);
PAINT MONO (-5410 2335);
FORCEPROP 0 LASTPIN (-5400 1425) $PN BL12
J 2
(-5410 1435);
DISPLAY 0.489362 (-5410 1435);
PAINT MONO (-5410 1435);
FORCEPROP 0 LASTPIN (-5400 1375) $PN BM13
J 2
(-5410 1385);
DISPLAY 0.489362 (-5410 1385);
PAINT MONO (-5410 1385);
FORCEPROP 0 LASTPIN (-5400 1275) $PN BR12
J 2
(-5410 1285);
DISPLAY 0.489362 (-5410 1285);
PAINT MONO (-5410 1285);
FORCEPROP 0 LASTPIN (-5400 3425) $PN BG14
J 2
(-5410 3435);
DISPLAY 0.489362 (-5410 3435);
PAINT MONO (-5410 3435);
FORCEPROP 0 LASTPIN (-5400 3375) $PN BH14
J 2
(-5410 3385);
DISPLAY 0.489362 (-5410 3385);
PAINT MONO (-5410 3385);
FORCEPROP 0 LASTPIN (-5400 3325) $PN BH13
J 2
(-5410 3335);
DISPLAY 0.489362 (-5410 3335);
PAINT MONO (-5410 3335);
FORCEPROP 0 LASTPIN (-5400 3275) $PN BJ12
J 2
(-5410 3285);
DISPLAY 0.489362 (-5410 3285);
PAINT MONO (-5410 3285);
FORCEPROP 0 LASTPIN (-5400 3225) $PN BJ14
J 2
(-5410 3235);
DISPLAY 0.489362 (-5410 3235);
PAINT MONO (-5410 3235);
FORCEPROP 0 LASTPIN (-5400 3175) $PN BK14
J 2
(-5410 3185);
DISPLAY 0.489362 (-5410 3185);
PAINT MONO (-5410 3185);
FORCEPROP 0 LASTPIN (-5400 3125) $PN BK13
J 2
(-5410 3135);
DISPLAY 0.489362 (-5410 3135);
PAINT MONO (-5410 3135);
FORCEPROP 0 LASTPIN (-3800 1925) $PN BY13
J 0
(-3790 1935);
DISPLAY 0.489362 (-3790 1935);
PAINT MONO (-3790 1935);
FORCEPROP 0 LASTPIN (-3800 1875) $PN CA14
J 0
(-3790 1885);
DISPLAY 0.489362 (-3790 1885);
PAINT MONO (-3790 1885);
FORCEPROP 0 LASTPIN (-3800 1825) $PN CA12
J 0
(-3790 1835);
DISPLAY 0.489362 (-3790 1835);
PAINT MONO (-3790 1835);
FORCEPROP 0 LASTPIN (-3800 1775) $PN CB14
J 0
(-3790 1785);
DISPLAY 0.489362 (-3790 1785);
PAINT MONO (-3790 1785);
FORCEPROP 0 LASTPIN (-3800 1725) $PN BT13
J 0
(-3790 1735);
DISPLAY 0.489362 (-3790 1735);
PAINT MONO (-3790 1735);
FORCEPROP 0 LASTPIN (-3800 1675) $PN BU14
J 0
(-3790 1685);
DISPLAY 0.489362 (-3790 1685);
PAINT MONO (-3790 1685);
FORCEPROP 0 LASTPIN (-3800 1625) $PN BU12
J 0
(-3790 1635);
DISPLAY 0.489362 (-3790 1635);
PAINT MONO (-3790 1635);
FORCEPROP 0 LASTPIN (-3800 1575) $PN BV14
J 0
(-3790 1585);
DISPLAY 0.489362 (-3790 1585);
PAINT MONO (-3790 1585);
FORCEPROP 0 LASTPIN (-3800 4175) $PN CB13
J 0
(-3790 4185);
DISPLAY 0.489362 (-3790 4185);
PAINT MONO (-3790 4185);
FORCEPROP 0 LASTPIN (-3800 4125) $PN CC14
J 0
(-3790 4135);
DISPLAY 0.489362 (-3790 4135);
PAINT MONO (-3790 4135);
FORCEPROP 0 LASTPIN (-3800 4075) $PN CC12
J 0
(-3790 4085);
DISPLAY 0.489362 (-3790 4085);
PAINT MONO (-3790 4085);
FORCEPROP 0 LASTPIN (-3800 4025) $PN CD14
J 0
(-3790 4035);
DISPLAY 0.489362 (-3790 4035);
PAINT MONO (-3790 4035);
FORCEPROP 0 LASTPIN (-3800 3975) $PN CF13
J 0
(-3790 3985);
DISPLAY 0.489362 (-3790 3985);
PAINT MONO (-3790 3985);
FORCEPROP 0 LASTPIN (-3800 3925) $PN CG14
J 0
(-3790 3935);
DISPLAY 0.489362 (-3790 3935);
PAINT MONO (-3790 3935);
FORCEPROP 0 LASTPIN (-3800 3875) $PN CG12
J 0
(-3790 3885);
DISPLAY 0.489362 (-3790 3885);
PAINT MONO (-3790 3885);
FORCEPROP 0 LASTPIN (-3800 3825) $PN CH14
J 0
(-3790 3835);
DISPLAY 0.489362 (-3790 3835);
PAINT MONO (-3790 3835);
FORCEPROP 0 LASTPIN (-3800 3725) $PN CH13
J 0
(-3790 3735);
DISPLAY 0.489362 (-3790 3735);
PAINT MONO (-3790 3735);
FORCEPROP 0 LASTPIN (-3800 3675) $PN CJ14
J 0
(-3790 3685);
DISPLAY 0.489362 (-3790 3685);
PAINT MONO (-3790 3685);
FORCEPROP 0 LASTPIN (-3800 3625) $PN CJ12
J 0
(-3790 3635);
DISPLAY 0.489362 (-3790 3635);
PAINT MONO (-3790 3635);
FORCEPROP 0 LASTPIN (-3800 3575) $PN CK14
J 0
(-3790 3585);
DISPLAY 0.489362 (-3790 3585);
PAINT MONO (-3790 3585);
FORCEPROP 0 LASTPIN (-3800 3525) $PN CM13
J 0
(-3790 3535);
DISPLAY 0.489362 (-3790 3535);
PAINT MONO (-3790 3535);
FORCEPROP 0 LASTPIN (-3800 3475) $PN CN14
J 0
(-3790 3485);
DISPLAY 0.489362 (-3790 3485);
PAINT MONO (-3790 3485);
FORCEPROP 0 LASTPIN (-3800 3425) $PN CN12
J 0
(-3790 3435);
DISPLAY 0.489362 (-3790 3435);
PAINT MONO (-3790 3435);
FORCEPROP 0 LASTPIN (-3800 3375) $PN CP14
J 0
(-3790 3385);
DISPLAY 0.489362 (-3790 3385);
PAINT MONO (-3790 3385);
FORCEPROP 0 LASTPIN (-3800 3275) $PN CP13
J 0
(-3790 3285);
DISPLAY 0.489362 (-3790 3285);
PAINT MONO (-3790 3285);
FORCEPROP 0 LASTPIN (-3800 3225) $PN CR14
J 0
(-3790 3235);
DISPLAY 0.489362 (-3790 3235);
PAINT MONO (-3790 3235);
FORCEPROP 0 LASTPIN (-3800 3175) $PN CR12
J 0
(-3790 3185);
DISPLAY 0.489362 (-3790 3185);
PAINT MONO (-3790 3185);
FORCEPROP 0 LASTPIN (-3800 3125) $PN CT14
J 0
(-3790 3135);
DISPLAY 0.489362 (-3790 3135);
PAINT MONO (-3790 3135);
FORCEPROP 0 LASTPIN (-3800 3075) $PN CV13
J 0
(-3790 3085);
DISPLAY 0.489362 (-3790 3085);
PAINT MONO (-3790 3085);
FORCEPROP 0 LASTPIN (-3800 3025) $PN CW14
J 0
(-3790 3035);
DISPLAY 0.489362 (-3790 3035);
PAINT MONO (-3790 3035);
FORCEPROP 0 LASTPIN (-3800 2975) $PN CW12
J 0
(-3790 2985);
DISPLAY 0.489362 (-3790 2985);
PAINT MONO (-3790 2985);
FORCEPROP 0 LASTPIN (-3800 2925) $PN CY14
J 0
(-3790 2935);
DISPLAY 0.489362 (-3790 2935);
PAINT MONO (-3790 2935);
FORCEPROP 0 LASTPIN (-3800 2825) $PN CY13
J 0
(-3790 2835);
DISPLAY 0.489362 (-3790 2835);
PAINT MONO (-3790 2835);
FORCEPROP 0 LASTPIN (-3800 2775) $PN DA14
J 0
(-3790 2785);
DISPLAY 0.489362 (-3790 2785);
PAINT MONO (-3790 2785);
FORCEPROP 0 LASTPIN (-3800 2725) $PN DA12
J 0
(-3790 2735);
DISPLAY 0.489362 (-3790 2735);
PAINT MONO (-3790 2735);
FORCEPROP 0 LASTPIN (-3800 2675) $PN DB14
J 0
(-3790 2685);
DISPLAY 0.489362 (-3790 2685);
PAINT MONO (-3790 2685);
FORCEPROP 0 LASTPIN (-3800 2625) $PN DD13
J 0
(-3790 2635);
DISPLAY 0.489362 (-3790 2635);
PAINT MONO (-3790 2635);
FORCEPROP 0 LASTPIN (-3800 2575) $PN DE14
J 0
(-3790 2585);
DISPLAY 0.489362 (-3790 2585);
PAINT MONO (-3790 2585);
FORCEPROP 0 LASTPIN (-3800 2525) $PN DE12
J 0
(-3790 2535);
DISPLAY 0.489362 (-3790 2535);
PAINT MONO (-3790 2535);
FORCEPROP 0 LASTPIN (-3800 2475) $PN DF14
J 0
(-3790 2485);
DISPLAY 0.489362 (-3790 2485);
PAINT MONO (-3790 2485);
FORCEPROP 0 LASTPIN (-5400 4925) $PN CD13
J 2
(-5410 4935);
DISPLAY 0.489362 (-5410 4935);
PAINT MONO (-5410 4935);
FORCEPROP 0 LASTPIN (-5400 4825) $PN CK13
J 2
(-5410 4835);
DISPLAY 0.489362 (-5410 4835);
PAINT MONO (-5410 4835);
FORCEPROP 0 LASTPIN (-5400 4725) $PN CT13
J 2
(-5410 4735);
DISPLAY 0.489362 (-5410 4735);
PAINT MONO (-5410 4735);
FORCEPROP 0 LASTPIN (-5400 4625) $PN DB13
J 2
(-5410 4635);
DISPLAY 0.489362 (-5410 4635);
PAINT MONO (-5410 4635);
FORCEPROP 0 LASTPIN (-5400 4525) $PN BY14
J 2
(-5410 4535);
DISPLAY 0.489362 (-5410 4535);
PAINT MONO (-5410 4535);
FORCEPROP 0 LASTPIN (-5400 4425) $PN CF14
J 2
(-5410 4435);
DISPLAY 0.489362 (-5410 4435);
PAINT MONO (-5410 4435);
FORCEPROP 0 LASTPIN (-5400 4325) $PN CM14
J 2
(-5410 4335);
DISPLAY 0.489362 (-5410 4335);
PAINT MONO (-5410 4335);
FORCEPROP 0 LASTPIN (-5400 4225) $PN CV14
J 2
(-5410 4235);
DISPLAY 0.489362 (-5410 4235);
PAINT MONO (-5410 4235);
FORCEPROP 0 LASTPIN (-5400 4125) $PN DD14
J 2
(-5410 4135);
DISPLAY 0.489362 (-5410 4135);
PAINT MONO (-5410 4135);
FORCEPROP 0 LASTPIN (-5400 4025) $PN BV13
J 2
(-5410 4035);
DISPLAY 0.489362 (-5410 4035);
PAINT MONO (-5410 4035);
FORCEPROP 0 LASTPIN (-5400 4875) $PN CE12
J 2
(-5410 4885);
DISPLAY 0.489362 (-5410 4885);
PAINT MONO (-5410 4885);
FORCEPROP 0 LASTPIN (-5400 4775) $PN CL12
J 2
(-5410 4785);
DISPLAY 0.489362 (-5410 4785);
PAINT MONO (-5410 4785);
FORCEPROP 0 LASTPIN (-5400 4675) $PN CU12
J 2
(-5410 4685);
DISPLAY 0.489362 (-5410 4685);
PAINT MONO (-5410 4685);
FORCEPROP 0 LASTPIN (-5400 4575) $PN DC12
J 2
(-5410 4585);
DISPLAY 0.489362 (-5410 4585);
PAINT MONO (-5410 4585);
FORCEPROP 0 LASTPIN (-5400 4475) $PN BW14
J 2
(-5410 4485);
DISPLAY 0.489362 (-5410 4485);
PAINT MONO (-5410 4485);
FORCEPROP 0 LASTPIN (-5400 4375) $PN CE14
J 2
(-5410 4385);
DISPLAY 0.489362 (-5410 4385);
PAINT MONO (-5410 4385);
FORCEPROP 0 LASTPIN (-5400 4275) $PN CL14
J 2
(-5410 4285);
DISPLAY 0.489362 (-5410 4285);
PAINT MONO (-5410 4285);
FORCEPROP 0 LASTPIN (-5400 4175) $PN CU14
J 2
(-5410 4185);
DISPLAY 0.489362 (-5410 4185);
PAINT MONO (-5410 4185);
FORCEPROP 0 LASTPIN (-5400 4075) $PN DC14
J 2
(-5410 4085);
DISPLAY 0.489362 (-5410 4085);
PAINT MONO (-5410 4085);
FORCEPROP 0 LASTPIN (-5400 3975) $PN BW12
J 2
(-5410 3985);
DISPLAY 0.489362 (-5410 3985);
PAINT MONO (-5410 3985);
FORCEPROP 0 LASTPIN (-5400 2225) $PN BL14
J 2
(-5410 2235);
DISPLAY 0.489362 (-5410 2235);
PAINT MONO (-5410 2235);
FORCEPROP 0 LASTPIN (-5400 1175) $PN BF14
J 2
(-5410 1185);
DISPLAY 0.489362 (-5410 1185);
PAINT MONO (-5410 1185);
FORCEPROP 2 LAST PART_TYPE SMLF
J 0
(-5250 6350);
DISPLAY 1.021277 (-5250 6350);
FORCEPROP 1 LAST MATERIAL IO
J 0
(-5245 6157);
DISPLAY 0.489362 (-5245 6157);
PAINT SKYBLUE (-5245 6157);
FORCEPROP 2 LAST VALUE SOCKET6096_13568-001
J 0
(-5250 6250);
DISPLAY 0.489362 (-5250 6250);
PAINT SKYBLUE (-5250 6250);
FORCEPROP 1 LAST PART_NUMBER DGA^6000030
J 0
(-5245 6284);
DISPLAY 0.489362 (-5245 6284);
PAINT SKYBLUE (-5245 6284);
FORCEPROP 2 LAST CDS_LIB pure_quanta
J 0
(-4600 3600);
DISPLAY INVISIBLE (-4600 3600);
FORCEPROP 1 LAST CDS_LMAN_SYM_OUTLINE -650,2525,650,-2525
J 0
(-4600 3600);
DISPLAY 0.468085 (-4600 3600);
PAINT GREEN (-4600 3600);
DISPLAY INVISIBLE (-4600 3600);
FORCEPROP 1 LAST NEEDS_NO_SIZE TRUE
J 0
(-4600 3600);
DISPLAY 0.723404 (-4600 3600);
PAINT GREEN (-4600 3600);
DISPLAY INVISIBLE (-4600 3600);
FORCEPROP 1 LAST PATH I159
J 0
(-4600 3600);
DISPLAY 0.723404 (-4600 3600);
PAINT GREEN (-4600 3600);
DISPLAY INVISIBLE (-4600 3600);
FORCEADD OFFPAGE..3
(-2600 6000);
FORCEPROP 2 LAST $XR0 92 
J 0
(-2386 6000);
DISPLAY 0.638298 (-2386 6000);
PAINT MONO (-2386 6000);
FORCEPROP 2 LAST PATH I160
J 0
(-2375 6050);
DISPLAY 1.021277 (-2375 6050);
DISPLAY INVISIBLE (-2375 6050);
FORCEPROP 1 LAST COMMENT_BODY TRUE
J 0
(-2650 5900);
DISPLAY 0.872340 (-2650 5900);
PAINT GREEN (-2650 5900);
DISPLAY INVISIBLE (-2650 5900);
FORCEPROP 1 LAST OFFPAGE TRUE
J 0
(-2275 5875);
DISPLAY 0.872340 (-2275 5875);
PAINT GREEN (-2275 5875);
DISPLAY INVISIBLE (-2275 5875);
FORCEPROP 2 LAST CDS_LIB mstr_standard
J 0
(-2600 6000);
DISPLAY 0.723404 (-2600 6000);
PAINT MONO (-2600 6000);
DISPLAY INVISIBLE (-2600 6000);
FORCEADD OFFPAGE..3
(-2600 4200);
FORCEPROP 2 LAST $XR0 92 
J 0
(-2386 4200);
DISPLAY 0.638298 (-2386 4200);
PAINT MONO (-2386 4200);
FORCEPROP 2 LAST PATH I161
J 0
(-2375 4250);
DISPLAY 1.021277 (-2375 4250);
DISPLAY INVISIBLE (-2375 4250);
FORCEPROP 1 LAST COMMENT_BODY TRUE
J 0
(-2650 4100);
DISPLAY 0.872340 (-2650 4100);
PAINT GREEN (-2650 4100);
DISPLAY INVISIBLE (-2650 4100);
FORCEPROP 1 LAST OFFPAGE TRUE
J 0
(-2275 4075);
DISPLAY 0.872340 (-2275 4075);
PAINT GREEN (-2275 4075);
DISPLAY INVISIBLE (-2275 4075);
FORCEPROP 2 LAST CDS_LIB mstr_standard
J 0
(-2600 4200);
DISPLAY 0.723404 (-2600 4200);
PAINT MONO (-2600 4200);
DISPLAY INVISIBLE (-2600 4200);
FORCEADD TAP..1
(-3325 5975);
FORCEPROP 3 LASTPIN (-3375 5975) SIG_NAME M_H_CPU0_SA_DQ<0>
J 0
(-3365 5985);
DISPLAY 0.659574 (-3365 5985);
PAINT MONO (-3365 5985);
DISPLAY INVISIBLE (-3365 5985);
FORCEPROP 1 LASTPIN (-3375 5975) BN 0
J 0
(-3387 5983);
DISPLAY 0.489362 (-3387 5983);
PAINT GREEN (-3387 5983);
FORCEPROP 2 LAST CDS_LIB mstr_standard
J 0
(-3325 5975);
DISPLAY 0.723404 (-3325 5975);
PAINT MONO (-3325 5975);
DISPLAY INVISIBLE (-3325 5975);
FORCEPROP 1 LAST BODY_TYPE PLUMBING
J 0
(-3325 6025);
DISPLAY 0.872340 (-3325 6025);
PAINT GREEN (-3325 6025);
DISPLAY INVISIBLE (-3325 6025);
FORCEPROP 1 LAST HDL_TAP TRUE
J 0
(-3000 5850);
DISPLAY 0.872340 (-3000 5850);
DISPLAY INVISIBLE (-3000 5850);
FORCEPROP 1 LAST PATH I162
J 0
(-3327 5975);
DISPLAY 0.872340 (-3327 5975);
PAINT GREEN (-3327 5975);
DISPLAY INVISIBLE (-3327 5975);
FORCEADD TAP..1
(-3325 5925);
FORCEPROP 3 LASTPIN (-3375 5925) SIG_NAME M_H_CPU0_SA_DQ<1>
J 0
(-3365 5935);
DISPLAY 0.659574 (-3365 5935);
PAINT MONO (-3365 5935);
DISPLAY INVISIBLE (-3365 5935);
FORCEPROP 1 LASTPIN (-3375 5925) BN 1
J 0
(-3387 5933);
DISPLAY 0.489362 (-3387 5933);
PAINT GREEN (-3387 5933);
FORCEPROP 2 LAST CDS_LIB mstr_standard
J 0
(-3325 5925);
DISPLAY 0.723404 (-3325 5925);
PAINT MONO (-3325 5925);
DISPLAY INVISIBLE (-3325 5925);
FORCEPROP 1 LAST BODY_TYPE PLUMBING
J 0
(-3325 5975);
DISPLAY 0.872340 (-3325 5975);
PAINT GREEN (-3325 5975);
DISPLAY INVISIBLE (-3325 5975);
FORCEPROP 1 LAST HDL_TAP TRUE
J 0
(-3000 5800);
DISPLAY 0.872340 (-3000 5800);
DISPLAY INVISIBLE (-3000 5800);
FORCEPROP 1 LAST PATH I163
J 0
(-3327 5925);
DISPLAY 0.872340 (-3327 5925);
PAINT GREEN (-3327 5925);
DISPLAY INVISIBLE (-3327 5925);
FORCEADD TAP..1
(-3325 5875);
FORCEPROP 3 LASTPIN (-3375 5875) SIG_NAME M_H_CPU0_SA_DQ<2>
J 0
(-3365 5885);
DISPLAY 0.659574 (-3365 5885);
PAINT MONO (-3365 5885);
DISPLAY INVISIBLE (-3365 5885);
FORCEPROP 1 LASTPIN (-3375 5875) BN 2
J 0
(-3387 5883);
DISPLAY 0.489362 (-3387 5883);
PAINT GREEN (-3387 5883);
FORCEPROP 2 LAST CDS_LIB mstr_standard
J 0
(-3325 5875);
DISPLAY 0.723404 (-3325 5875);
PAINT MONO (-3325 5875);
DISPLAY INVISIBLE (-3325 5875);
FORCEPROP 1 LAST BODY_TYPE PLUMBING
J 0
(-3325 5925);
DISPLAY 0.872340 (-3325 5925);
PAINT GREEN (-3325 5925);
DISPLAY INVISIBLE (-3325 5925);
FORCEPROP 1 LAST HDL_TAP TRUE
J 0
(-3000 5750);
DISPLAY 0.872340 (-3000 5750);
DISPLAY INVISIBLE (-3000 5750);
FORCEPROP 1 LAST PATH I164
J 0
(-3327 5875);
DISPLAY 0.872340 (-3327 5875);
PAINT GREEN (-3327 5875);
DISPLAY INVISIBLE (-3327 5875);
FORCEADD TAP..1
(-3325 5825);
FORCEPROP 3 LASTPIN (-3375 5825) SIG_NAME M_H_CPU0_SA_DQ<3>
J 0
(-3365 5835);
DISPLAY 0.659574 (-3365 5835);
PAINT MONO (-3365 5835);
DISPLAY INVISIBLE (-3365 5835);
FORCEPROP 1 LASTPIN (-3375 5825) BN 3
J 0
(-3387 5833);
DISPLAY 0.489362 (-3387 5833);
PAINT GREEN (-3387 5833);
FORCEPROP 2 LAST CDS_LIB mstr_standard
J 0
(-3325 5825);
DISPLAY 0.723404 (-3325 5825);
PAINT MONO (-3325 5825);
DISPLAY INVISIBLE (-3325 5825);
FORCEPROP 1 LAST BODY_TYPE PLUMBING
J 0
(-3325 5875);
DISPLAY 0.872340 (-3325 5875);
PAINT GREEN (-3325 5875);
DISPLAY INVISIBLE (-3325 5875);
FORCEPROP 1 LAST HDL_TAP TRUE
J 0
(-3000 5700);
DISPLAY 0.872340 (-3000 5700);
DISPLAY INVISIBLE (-3000 5700);
FORCEPROP 1 LAST PATH I165
J 0
(-3327 5825);
DISPLAY 0.872340 (-3327 5825);
PAINT GREEN (-3327 5825);
DISPLAY INVISIBLE (-3327 5825);
FORCEADD TAP..1
(-3325 5775);
FORCEPROP 3 LASTPIN (-3375 5775) SIG_NAME M_H_CPU0_SA_DQ<4>
J 0
(-3365 5785);
DISPLAY 0.659574 (-3365 5785);
PAINT MONO (-3365 5785);
DISPLAY INVISIBLE (-3365 5785);
FORCEPROP 1 LASTPIN (-3375 5775) BN 4
J 0
(-3387 5783);
DISPLAY 0.489362 (-3387 5783);
PAINT GREEN (-3387 5783);
FORCEPROP 2 LAST CDS_LIB mstr_standard
J 0
(-3325 5775);
DISPLAY 0.723404 (-3325 5775);
PAINT MONO (-3325 5775);
DISPLAY INVISIBLE (-3325 5775);
FORCEPROP 1 LAST BODY_TYPE PLUMBING
J 0
(-3325 5825);
DISPLAY 0.872340 (-3325 5825);
PAINT GREEN (-3325 5825);
DISPLAY INVISIBLE (-3325 5825);
FORCEPROP 1 LAST HDL_TAP TRUE
J 0
(-3000 5650);
DISPLAY 0.872340 (-3000 5650);
DISPLAY INVISIBLE (-3000 5650);
FORCEPROP 1 LAST PATH I166
J 0
(-3327 5775);
DISPLAY 0.872340 (-3327 5775);
PAINT GREEN (-3327 5775);
DISPLAY INVISIBLE (-3327 5775);
FORCEADD TAP..1
(-3325 5675);
FORCEPROP 3 LASTPIN (-3375 5675) SIG_NAME M_H_CPU0_SA_DQ<6>
J 0
(-3365 5685);
DISPLAY 0.659574 (-3365 5685);
PAINT MONO (-3365 5685);
DISPLAY INVISIBLE (-3365 5685);
FORCEPROP 1 LASTPIN (-3375 5675) BN 6
J 0
(-3387 5683);
DISPLAY 0.489362 (-3387 5683);
PAINT GREEN (-3387 5683);
FORCEPROP 2 LAST CDS_LIB mstr_standard
J 0
(-3325 5675);
DISPLAY 0.723404 (-3325 5675);
PAINT MONO (-3325 5675);
DISPLAY INVISIBLE (-3325 5675);
FORCEPROP 1 LAST BODY_TYPE PLUMBING
J 0
(-3325 5725);
DISPLAY 0.872340 (-3325 5725);
PAINT GREEN (-3325 5725);
DISPLAY INVISIBLE (-3325 5725);
FORCEPROP 1 LAST HDL_TAP TRUE
J 0
(-3000 5550);
DISPLAY 0.872340 (-3000 5550);
DISPLAY INVISIBLE (-3000 5550);
FORCEPROP 1 LAST PATH I167
J 0
(-3327 5675);
DISPLAY 0.872340 (-3327 5675);
PAINT GREEN (-3327 5675);
DISPLAY INVISIBLE (-3327 5675);
FORCEADD TAP..1
(-3325 5725);
FORCEPROP 3 LASTPIN (-3375 5725) SIG_NAME M_H_CPU0_SA_DQ<5>
J 0
(-3365 5735);
DISPLAY 0.659574 (-3365 5735);
PAINT MONO (-3365 5735);
DISPLAY INVISIBLE (-3365 5735);
FORCEPROP 1 LASTPIN (-3375 5725) BN 5
J 0
(-3387 5733);
DISPLAY 0.489362 (-3387 5733);
PAINT GREEN (-3387 5733);
FORCEPROP 2 LAST CDS_LIB mstr_standard
J 0
(-3325 5725);
DISPLAY 0.723404 (-3325 5725);
PAINT MONO (-3325 5725);
DISPLAY INVISIBLE (-3325 5725);
FORCEPROP 1 LAST BODY_TYPE PLUMBING
J 0
(-3325 5775);
DISPLAY 0.872340 (-3325 5775);
PAINT GREEN (-3325 5775);
DISPLAY INVISIBLE (-3325 5775);
FORCEPROP 1 LAST HDL_TAP TRUE
J 0
(-3000 5600);
DISPLAY 0.872340 (-3000 5600);
DISPLAY INVISIBLE (-3000 5600);
FORCEPROP 1 LAST PATH I168
J 0
(-3327 5725);
DISPLAY 0.872340 (-3327 5725);
PAINT GREEN (-3327 5725);
DISPLAY INVISIBLE (-3327 5725);
FORCEADD TAP..1
(-3325 5425);
FORCEPROP 3 LASTPIN (-3375 5425) SIG_NAME M_H_CPU0_SA_DQ<10>
J 0
(-3365 5435);
DISPLAY 0.659574 (-3365 5435);
PAINT MONO (-3365 5435);
DISPLAY INVISIBLE (-3365 5435);
FORCEPROP 1 LASTPIN (-3375 5425) BN 10
J 0
(-3387 5433);
DISPLAY 0.489362 (-3387 5433);
PAINT GREEN (-3387 5433);
FORCEPROP 2 LAST CDS_LIB mstr_standard
J 0
(-3325 5425);
DISPLAY 0.723404 (-3325 5425);
PAINT MONO (-3325 5425);
DISPLAY INVISIBLE (-3325 5425);
FORCEPROP 1 LAST BODY_TYPE PLUMBING
J 0
(-3325 5475);
DISPLAY 0.872340 (-3325 5475);
PAINT GREEN (-3325 5475);
DISPLAY INVISIBLE (-3325 5475);
FORCEPROP 1 LAST HDL_TAP TRUE
J 0
(-3000 5300);
DISPLAY 0.872340 (-3000 5300);
DISPLAY INVISIBLE (-3000 5300);
FORCEPROP 1 LAST PATH I169
J 0
(-3327 5425);
DISPLAY 0.872340 (-3327 5425);
PAINT GREEN (-3327 5425);
DISPLAY INVISIBLE (-3327 5425);
FORCEADD TAP..1
(-3325 5525);
FORCEPROP 3 LASTPIN (-3375 5525) SIG_NAME M_H_CPU0_SA_DQ<8>
J 0
(-3365 5535);
DISPLAY 0.659574 (-3365 5535);
PAINT MONO (-3365 5535);
DISPLAY INVISIBLE (-3365 5535);
FORCEPROP 1 LASTPIN (-3375 5525) BN 8
J 0
(-3387 5533);
DISPLAY 0.489362 (-3387 5533);
PAINT GREEN (-3387 5533);
FORCEPROP 2 LAST CDS_LIB mstr_standard
J 0
(-3325 5525);
DISPLAY 0.723404 (-3325 5525);
PAINT MONO (-3325 5525);
DISPLAY INVISIBLE (-3325 5525);
FORCEPROP 1 LAST BODY_TYPE PLUMBING
J 0
(-3325 5575);
DISPLAY 0.872340 (-3325 5575);
PAINT GREEN (-3325 5575);
DISPLAY INVISIBLE (-3325 5575);
FORCEPROP 1 LAST HDL_TAP TRUE
J 0
(-3000 5400);
DISPLAY 0.872340 (-3000 5400);
DISPLAY INVISIBLE (-3000 5400);
FORCEPROP 1 LAST PATH I170
J 0
(-3327 5525);
DISPLAY 0.872340 (-3327 5525);
PAINT GREEN (-3327 5525);
DISPLAY INVISIBLE (-3327 5525);
FORCEADD TAP..1
(-3325 5625);
FORCEPROP 3 LASTPIN (-3375 5625) SIG_NAME M_H_CPU0_SA_DQ<7>
J 0
(-3365 5635);
DISPLAY 0.659574 (-3365 5635);
PAINT MONO (-3365 5635);
DISPLAY INVISIBLE (-3365 5635);
FORCEPROP 1 LASTPIN (-3375 5625) BN 7
J 0
(-3387 5633);
DISPLAY 0.489362 (-3387 5633);
PAINT GREEN (-3387 5633);
FORCEPROP 2 LAST CDS_LIB mstr_standard
J 0
(-3325 5625);
DISPLAY 0.723404 (-3325 5625);
PAINT MONO (-3325 5625);
DISPLAY INVISIBLE (-3325 5625);
FORCEPROP 1 LAST BODY_TYPE PLUMBING
J 0
(-3325 5675);
DISPLAY 0.872340 (-3325 5675);
PAINT GREEN (-3325 5675);
DISPLAY INVISIBLE (-3325 5675);
FORCEPROP 1 LAST HDL_TAP TRUE
J 0
(-3000 5500);
DISPLAY 0.872340 (-3000 5500);
DISPLAY INVISIBLE (-3000 5500);
FORCEPROP 1 LAST PATH I171
J 0
(-3327 5625);
DISPLAY 0.872340 (-3327 5625);
PAINT GREEN (-3327 5625);
DISPLAY INVISIBLE (-3327 5625);
FORCEADD TAP..1
(-3325 5475);
FORCEPROP 3 LASTPIN (-3375 5475) SIG_NAME M_H_CPU0_SA_DQ<9>
J 0
(-3365 5485);
DISPLAY 0.659574 (-3365 5485);
PAINT MONO (-3365 5485);
DISPLAY INVISIBLE (-3365 5485);
FORCEPROP 1 LASTPIN (-3375 5475) BN 9
J 0
(-3387 5483);
DISPLAY 0.489362 (-3387 5483);
PAINT GREEN (-3387 5483);
FORCEPROP 2 LAST CDS_LIB mstr_standard
J 0
(-3325 5475);
DISPLAY 0.723404 (-3325 5475);
PAINT MONO (-3325 5475);
DISPLAY INVISIBLE (-3325 5475);
FORCEPROP 1 LAST BODY_TYPE PLUMBING
J 0
(-3325 5525);
DISPLAY 0.872340 (-3325 5525);
PAINT GREEN (-3325 5525);
DISPLAY INVISIBLE (-3325 5525);
FORCEPROP 1 LAST HDL_TAP TRUE
J 0
(-3000 5350);
DISPLAY 0.872340 (-3000 5350);
DISPLAY INVISIBLE (-3000 5350);
FORCEPROP 1 LAST PATH I172
J 0
(-3327 5475);
DISPLAY 0.872340 (-3327 5475);
PAINT GREEN (-3327 5475);
DISPLAY INVISIBLE (-3327 5475);
FORCEADD TAP..1
(-3325 5225);
FORCEPROP 3 LASTPIN (-3375 5225) SIG_NAME M_H_CPU0_SA_DQ<14>
J 0
(-3365 5235);
DISPLAY 0.659574 (-3365 5235);
PAINT MONO (-3365 5235);
DISPLAY INVISIBLE (-3365 5235);
FORCEPROP 1 LASTPIN (-3375 5225) BN 14
J 0
(-3387 5233);
DISPLAY 0.489362 (-3387 5233);
PAINT GREEN (-3387 5233);
FORCEPROP 2 LAST CDS_LIB mstr_standard
J 0
(-3325 5225);
DISPLAY 0.723404 (-3325 5225);
PAINT MONO (-3325 5225);
DISPLAY INVISIBLE (-3325 5225);
FORCEPROP 1 LAST BODY_TYPE PLUMBING
J 0
(-3325 5275);
DISPLAY 0.872340 (-3325 5275);
PAINT GREEN (-3325 5275);
DISPLAY INVISIBLE (-3325 5275);
FORCEPROP 1 LAST HDL_TAP TRUE
J 0
(-3000 5100);
DISPLAY 0.872340 (-3000 5100);
DISPLAY INVISIBLE (-3000 5100);
FORCEPROP 1 LAST PATH I173
J 0
(-3327 5225);
DISPLAY 0.872340 (-3327 5225);
PAINT GREEN (-3327 5225);
DISPLAY INVISIBLE (-3327 5225);
FORCEADD TAP..1
(-3325 5175);
FORCEPROP 3 LASTPIN (-3375 5175) SIG_NAME M_H_CPU0_SA_DQ<15>
J 0
(-3365 5185);
DISPLAY 0.659574 (-3365 5185);
PAINT MONO (-3365 5185);
DISPLAY INVISIBLE (-3365 5185);
FORCEPROP 1 LASTPIN (-3375 5175) BN 15
J 0
(-3387 5183);
DISPLAY 0.489362 (-3387 5183);
PAINT GREEN (-3387 5183);
FORCEPROP 2 LAST CDS_LIB mstr_standard
J 0
(-3325 5175);
DISPLAY 0.723404 (-3325 5175);
PAINT MONO (-3325 5175);
DISPLAY INVISIBLE (-3325 5175);
FORCEPROP 1 LAST BODY_TYPE PLUMBING
J 0
(-3325 5225);
DISPLAY 0.872340 (-3325 5225);
PAINT GREEN (-3325 5225);
DISPLAY INVISIBLE (-3325 5225);
FORCEPROP 1 LAST HDL_TAP TRUE
J 0
(-3000 5050);
DISPLAY 0.872340 (-3000 5050);
DISPLAY INVISIBLE (-3000 5050);
FORCEPROP 1 LAST PATH I174
J 0
(-3327 5175);
DISPLAY 0.872340 (-3327 5175);
PAINT GREEN (-3327 5175);
DISPLAY INVISIBLE (-3327 5175);
FORCEADD TAP..1
(-3325 5275);
FORCEPROP 3 LASTPIN (-3375 5275) SIG_NAME M_H_CPU0_SA_DQ<13>
J 0
(-3365 5285);
DISPLAY 0.659574 (-3365 5285);
PAINT MONO (-3365 5285);
DISPLAY INVISIBLE (-3365 5285);
FORCEPROP 1 LASTPIN (-3375 5275) BN 13
J 0
(-3387 5283);
DISPLAY 0.489362 (-3387 5283);
PAINT GREEN (-3387 5283);
FORCEPROP 2 LAST CDS_LIB mstr_standard
J 0
(-3325 5275);
DISPLAY 0.723404 (-3325 5275);
PAINT MONO (-3325 5275);
DISPLAY INVISIBLE (-3325 5275);
FORCEPROP 1 LAST BODY_TYPE PLUMBING
J 0
(-3325 5325);
DISPLAY 0.872340 (-3325 5325);
PAINT GREEN (-3325 5325);
DISPLAY INVISIBLE (-3325 5325);
FORCEPROP 1 LAST HDL_TAP TRUE
J 0
(-3000 5150);
DISPLAY 0.872340 (-3000 5150);
DISPLAY INVISIBLE (-3000 5150);
FORCEPROP 1 LAST PATH I175
J 0
(-3327 5275);
DISPLAY 0.872340 (-3327 5275);
PAINT GREEN (-3327 5275);
DISPLAY INVISIBLE (-3327 5275);
FORCEADD TAP..1
(-3325 5325);
FORCEPROP 3 LASTPIN (-3375 5325) SIG_NAME M_H_CPU0_SA_DQ<12>
J 0
(-3365 5335);
DISPLAY 0.659574 (-3365 5335);
PAINT MONO (-3365 5335);
DISPLAY INVISIBLE (-3365 5335);
FORCEPROP 1 LASTPIN (-3375 5325) BN 12
J 0
(-3387 5333);
DISPLAY 0.489362 (-3387 5333);
PAINT GREEN (-3387 5333);
FORCEPROP 2 LAST CDS_LIB mstr_standard
J 0
(-3325 5325);
DISPLAY 0.723404 (-3325 5325);
PAINT MONO (-3325 5325);
DISPLAY INVISIBLE (-3325 5325);
FORCEPROP 1 LAST BODY_TYPE PLUMBING
J 0
(-3325 5375);
DISPLAY 0.872340 (-3325 5375);
PAINT GREEN (-3325 5375);
DISPLAY INVISIBLE (-3325 5375);
FORCEPROP 1 LAST HDL_TAP TRUE
J 0
(-3000 5200);
DISPLAY 0.872340 (-3000 5200);
DISPLAY INVISIBLE (-3000 5200);
FORCEPROP 1 LAST PATH I176
J 0
(-3327 5325);
DISPLAY 0.872340 (-3327 5325);
PAINT GREEN (-3327 5325);
DISPLAY INVISIBLE (-3327 5325);
FORCEADD TAP..1
(-3325 5375);
FORCEPROP 3 LASTPIN (-3375 5375) SIG_NAME M_H_CPU0_SA_DQ<11>
J 0
(-3365 5385);
DISPLAY 0.659574 (-3365 5385);
PAINT MONO (-3365 5385);
DISPLAY INVISIBLE (-3365 5385);
FORCEPROP 1 LASTPIN (-3375 5375) BN 11
J 0
(-3387 5383);
DISPLAY 0.489362 (-3387 5383);
PAINT GREEN (-3387 5383);
FORCEPROP 2 LAST CDS_LIB mstr_standard
J 0
(-3325 5375);
DISPLAY 0.723404 (-3325 5375);
PAINT MONO (-3325 5375);
DISPLAY INVISIBLE (-3325 5375);
FORCEPROP 1 LAST BODY_TYPE PLUMBING
J 0
(-3325 5425);
DISPLAY 0.872340 (-3325 5425);
PAINT GREEN (-3325 5425);
DISPLAY INVISIBLE (-3325 5425);
FORCEPROP 1 LAST HDL_TAP TRUE
J 0
(-3000 5250);
DISPLAY 0.872340 (-3000 5250);
DISPLAY INVISIBLE (-3000 5250);
FORCEPROP 1 LAST PATH I177
J 0
(-3327 5375);
DISPLAY 0.872340 (-3327 5375);
PAINT GREEN (-3327 5375);
DISPLAY INVISIBLE (-3327 5375);
FORCEADD TAP..1
(-3325 4975);
FORCEPROP 3 LASTPIN (-3375 4975) SIG_NAME M_H_CPU0_SA_DQ<18>
J 0
(-3365 4985);
DISPLAY 0.659574 (-3365 4985);
PAINT MONO (-3365 4985);
DISPLAY INVISIBLE (-3365 4985);
FORCEPROP 1 LASTPIN (-3375 4975) BN 18
J 0
(-3387 4983);
DISPLAY 0.489362 (-3387 4983);
PAINT GREEN (-3387 4983);
FORCEPROP 2 LAST CDS_LIB mstr_standard
J 0
(-3325 4975);
DISPLAY 0.723404 (-3325 4975);
PAINT MONO (-3325 4975);
DISPLAY INVISIBLE (-3325 4975);
FORCEPROP 1 LAST BODY_TYPE PLUMBING
J 0
(-3325 5025);
DISPLAY 0.872340 (-3325 5025);
PAINT GREEN (-3325 5025);
DISPLAY INVISIBLE (-3325 5025);
FORCEPROP 1 LAST HDL_TAP TRUE
J 0
(-3000 4850);
DISPLAY 0.872340 (-3000 4850);
DISPLAY INVISIBLE (-3000 4850);
FORCEPROP 1 LAST PATH I178
J 0
(-3327 4975);
DISPLAY 0.872340 (-3327 4975);
PAINT GREEN (-3327 4975);
DISPLAY INVISIBLE (-3327 4975);
FORCEADD TAP..1
(-3325 4925);
FORCEPROP 3 LASTPIN (-3375 4925) SIG_NAME M_H_CPU0_SA_DQ<19>
J 0
(-3365 4935);
DISPLAY 0.659574 (-3365 4935);
PAINT MONO (-3365 4935);
DISPLAY INVISIBLE (-3365 4935);
FORCEPROP 1 LASTPIN (-3375 4925) BN 19
J 0
(-3387 4933);
DISPLAY 0.489362 (-3387 4933);
PAINT GREEN (-3387 4933);
FORCEPROP 2 LAST CDS_LIB mstr_standard
J 0
(-3325 4925);
DISPLAY 0.723404 (-3325 4925);
PAINT MONO (-3325 4925);
DISPLAY INVISIBLE (-3325 4925);
FORCEPROP 1 LAST BODY_TYPE PLUMBING
J 0
(-3325 4975);
DISPLAY 0.872340 (-3325 4975);
PAINT GREEN (-3325 4975);
DISPLAY INVISIBLE (-3325 4975);
FORCEPROP 1 LAST HDL_TAP TRUE
J 0
(-3000 4800);
DISPLAY 0.872340 (-3000 4800);
DISPLAY INVISIBLE (-3000 4800);
FORCEPROP 1 LAST PATH I179
J 0
(-3327 4925);
DISPLAY 0.872340 (-3327 4925);
PAINT GREEN (-3327 4925);
DISPLAY INVISIBLE (-3327 4925);
FORCEADD TAP..1
(-3325 4875);
FORCEPROP 3 LASTPIN (-3375 4875) SIG_NAME M_H_CPU0_SA_DQ<20>
J 0
(-3365 4885);
DISPLAY 0.659574 (-3365 4885);
PAINT MONO (-3365 4885);
DISPLAY INVISIBLE (-3365 4885);
FORCEPROP 1 LASTPIN (-3375 4875) BN 20
J 0
(-3387 4883);
DISPLAY 0.489362 (-3387 4883);
PAINT GREEN (-3387 4883);
FORCEPROP 2 LAST CDS_LIB mstr_standard
J 0
(-3325 4875);
DISPLAY 0.723404 (-3325 4875);
PAINT MONO (-3325 4875);
DISPLAY INVISIBLE (-3325 4875);
FORCEPROP 1 LAST BODY_TYPE PLUMBING
J 0
(-3325 4925);
DISPLAY 0.872340 (-3325 4925);
PAINT GREEN (-3325 4925);
DISPLAY INVISIBLE (-3325 4925);
FORCEPROP 1 LAST HDL_TAP TRUE
J 0
(-3000 4750);
DISPLAY 0.872340 (-3000 4750);
DISPLAY INVISIBLE (-3000 4750);
FORCEPROP 1 LAST PATH I180
J 0
(-3327 4875);
DISPLAY 0.872340 (-3327 4875);
PAINT GREEN (-3327 4875);
DISPLAY INVISIBLE (-3327 4875);
FORCEADD TAP..1
(-3325 5025);
FORCEPROP 3 LASTPIN (-3375 5025) SIG_NAME M_H_CPU0_SA_DQ<17>
J 0
(-3365 5035);
DISPLAY 0.659574 (-3365 5035);
PAINT MONO (-3365 5035);
DISPLAY INVISIBLE (-3365 5035);
FORCEPROP 1 LASTPIN (-3375 5025) BN 17
J 0
(-3387 5033);
DISPLAY 0.489362 (-3387 5033);
PAINT GREEN (-3387 5033);
FORCEPROP 2 LAST CDS_LIB mstr_standard
J 0
(-3325 5025);
DISPLAY 0.723404 (-3325 5025);
PAINT MONO (-3325 5025);
DISPLAY INVISIBLE (-3325 5025);
FORCEPROP 1 LAST BODY_TYPE PLUMBING
J 0
(-3325 5075);
DISPLAY 0.872340 (-3325 5075);
PAINT GREEN (-3325 5075);
DISPLAY INVISIBLE (-3325 5075);
FORCEPROP 1 LAST HDL_TAP TRUE
J 0
(-3000 4900);
DISPLAY 0.872340 (-3000 4900);
DISPLAY INVISIBLE (-3000 4900);
FORCEPROP 1 LAST PATH I181
J 0
(-3327 5025);
DISPLAY 0.872340 (-3327 5025);
PAINT GREEN (-3327 5025);
DISPLAY INVISIBLE (-3327 5025);
FORCEADD TAP..1
(-3325 5075);
FORCEPROP 3 LASTPIN (-3375 5075) SIG_NAME M_H_CPU0_SA_DQ<16>
J 0
(-3365 5085);
DISPLAY 0.659574 (-3365 5085);
PAINT MONO (-3365 5085);
DISPLAY INVISIBLE (-3365 5085);
FORCEPROP 1 LASTPIN (-3375 5075) BN 16
J 0
(-3387 5083);
DISPLAY 0.489362 (-3387 5083);
PAINT GREEN (-3387 5083);
FORCEPROP 2 LAST CDS_LIB mstr_standard
J 0
(-3325 5075);
DISPLAY 0.723404 (-3325 5075);
PAINT MONO (-3325 5075);
DISPLAY INVISIBLE (-3325 5075);
FORCEPROP 1 LAST BODY_TYPE PLUMBING
J 0
(-3325 5125);
DISPLAY 0.872340 (-3325 5125);
PAINT GREEN (-3325 5125);
DISPLAY INVISIBLE (-3325 5125);
FORCEPROP 1 LAST HDL_TAP TRUE
J 0
(-3000 4950);
DISPLAY 0.872340 (-3000 4950);
DISPLAY INVISIBLE (-3000 4950);
FORCEPROP 1 LAST PATH I182
J 0
(-3327 5075);
DISPLAY 0.872340 (-3327 5075);
PAINT GREEN (-3327 5075);
DISPLAY INVISIBLE (-3327 5075);
FORCEADD TAP..1
(-3325 4625);
FORCEPROP 3 LASTPIN (-3375 4625) SIG_NAME M_H_CPU0_SA_DQ<24>
J 0
(-3365 4635);
DISPLAY 0.659574 (-3365 4635);
PAINT MONO (-3365 4635);
DISPLAY INVISIBLE (-3365 4635);
FORCEPROP 1 LASTPIN (-3375 4625) BN 24
J 0
(-3387 4633);
DISPLAY 0.489362 (-3387 4633);
PAINT GREEN (-3387 4633);
FORCEPROP 2 LAST CDS_LIB mstr_standard
J 0
(-3325 4625);
DISPLAY 0.723404 (-3325 4625);
PAINT MONO (-3325 4625);
DISPLAY INVISIBLE (-3325 4625);
FORCEPROP 1 LAST BODY_TYPE PLUMBING
J 0
(-3325 4675);
DISPLAY 0.872340 (-3325 4675);
PAINT GREEN (-3325 4675);
DISPLAY INVISIBLE (-3325 4675);
FORCEPROP 1 LAST HDL_TAP TRUE
J 0
(-3000 4500);
DISPLAY 0.872340 (-3000 4500);
DISPLAY INVISIBLE (-3000 4500);
FORCEPROP 1 LAST PATH I183
J 0
(-3327 4625);
DISPLAY 0.872340 (-3327 4625);
PAINT GREEN (-3327 4625);
DISPLAY INVISIBLE (-3327 4625);
FORCEADD TAP..1
(-3325 4725);
FORCEPROP 3 LASTPIN (-3375 4725) SIG_NAME M_H_CPU0_SA_DQ<23>
J 0
(-3365 4735);
DISPLAY 0.659574 (-3365 4735);
PAINT MONO (-3365 4735);
DISPLAY INVISIBLE (-3365 4735);
FORCEPROP 1 LASTPIN (-3375 4725) BN 23
J 0
(-3387 4733);
DISPLAY 0.489362 (-3387 4733);
PAINT GREEN (-3387 4733);
FORCEPROP 2 LAST CDS_LIB mstr_standard
J 0
(-3325 4725);
DISPLAY 0.723404 (-3325 4725);
PAINT MONO (-3325 4725);
DISPLAY INVISIBLE (-3325 4725);
FORCEPROP 1 LAST BODY_TYPE PLUMBING
J 0
(-3325 4775);
DISPLAY 0.872340 (-3325 4775);
PAINT GREEN (-3325 4775);
DISPLAY INVISIBLE (-3325 4775);
FORCEPROP 1 LAST HDL_TAP TRUE
J 0
(-3000 4600);
DISPLAY 0.872340 (-3000 4600);
DISPLAY INVISIBLE (-3000 4600);
FORCEPROP 1 LAST PATH I184
J 0
(-3327 4725);
DISPLAY 0.872340 (-3327 4725);
PAINT GREEN (-3327 4725);
DISPLAY INVISIBLE (-3327 4725);
FORCEADD TAP..1
(-3325 4775);
FORCEPROP 3 LASTPIN (-3375 4775) SIG_NAME M_H_CPU0_SA_DQ<22>
J 0
(-3365 4785);
DISPLAY 0.659574 (-3365 4785);
PAINT MONO (-3365 4785);
DISPLAY INVISIBLE (-3365 4785);
FORCEPROP 1 LASTPIN (-3375 4775) BN 22
J 0
(-3387 4783);
DISPLAY 0.489362 (-3387 4783);
PAINT GREEN (-3387 4783);
FORCEPROP 2 LAST CDS_LIB mstr_standard
J 0
(-3325 4775);
DISPLAY 0.723404 (-3325 4775);
PAINT MONO (-3325 4775);
DISPLAY INVISIBLE (-3325 4775);
FORCEPROP 1 LAST BODY_TYPE PLUMBING
J 0
(-3325 4825);
DISPLAY 0.872340 (-3325 4825);
PAINT GREEN (-3325 4825);
DISPLAY INVISIBLE (-3325 4825);
FORCEPROP 1 LAST HDL_TAP TRUE
J 0
(-3000 4650);
DISPLAY 0.872340 (-3000 4650);
DISPLAY INVISIBLE (-3000 4650);
FORCEPROP 1 LAST PATH I185
J 0
(-3327 4775);
DISPLAY 0.872340 (-3327 4775);
PAINT GREEN (-3327 4775);
DISPLAY INVISIBLE (-3327 4775);
FORCEADD TAP..1
(-3325 4825);
FORCEPROP 3 LASTPIN (-3375 4825) SIG_NAME M_H_CPU0_SA_DQ<21>
J 0
(-3365 4835);
DISPLAY 0.659574 (-3365 4835);
PAINT MONO (-3365 4835);
DISPLAY INVISIBLE (-3365 4835);
FORCEPROP 1 LASTPIN (-3375 4825) BN 21
J 0
(-3387 4833);
DISPLAY 0.489362 (-3387 4833);
PAINT GREEN (-3387 4833);
FORCEPROP 2 LAST CDS_LIB mstr_standard
J 0
(-3325 4825);
DISPLAY 0.723404 (-3325 4825);
PAINT MONO (-3325 4825);
DISPLAY INVISIBLE (-3325 4825);
FORCEPROP 1 LAST BODY_TYPE PLUMBING
J 0
(-3325 4875);
DISPLAY 0.872340 (-3325 4875);
PAINT GREEN (-3325 4875);
DISPLAY INVISIBLE (-3325 4875);
FORCEPROP 1 LAST HDL_TAP TRUE
J 0
(-3000 4700);
DISPLAY 0.872340 (-3000 4700);
DISPLAY INVISIBLE (-3000 4700);
FORCEPROP 1 LAST PATH I186
J 0
(-3327 4825);
DISPLAY 0.872340 (-3327 4825);
PAINT GREEN (-3327 4825);
DISPLAY INVISIBLE (-3327 4825);
FORCEADD TAP..1
(-3325 4475);
FORCEPROP 3 LASTPIN (-3375 4475) SIG_NAME M_H_CPU0_SA_DQ<27>
J 0
(-3365 4485);
DISPLAY 0.659574 (-3365 4485);
PAINT MONO (-3365 4485);
DISPLAY INVISIBLE (-3365 4485);
FORCEPROP 1 LASTPIN (-3375 4475) BN 27
J 0
(-3387 4483);
DISPLAY 0.489362 (-3387 4483);
PAINT GREEN (-3387 4483);
FORCEPROP 2 LAST CDS_LIB mstr_standard
J 0
(-3325 4475);
DISPLAY 0.723404 (-3325 4475);
PAINT MONO (-3325 4475);
DISPLAY INVISIBLE (-3325 4475);
FORCEPROP 1 LAST BODY_TYPE PLUMBING
J 0
(-3325 4525);
DISPLAY 0.872340 (-3325 4525);
PAINT GREEN (-3325 4525);
DISPLAY INVISIBLE (-3325 4525);
FORCEPROP 1 LAST HDL_TAP TRUE
J 0
(-3000 4350);
DISPLAY 0.872340 (-3000 4350);
DISPLAY INVISIBLE (-3000 4350);
FORCEPROP 1 LAST PATH I187
J 0
(-3327 4475);
DISPLAY 0.872340 (-3327 4475);
PAINT GREEN (-3327 4475);
DISPLAY INVISIBLE (-3327 4475);
FORCEADD TAP..1
(-3325 4425);
FORCEPROP 3 LASTPIN (-3375 4425) SIG_NAME M_H_CPU0_SA_DQ<28>
J 0
(-3365 4435);
DISPLAY 0.659574 (-3365 4435);
PAINT MONO (-3365 4435);
DISPLAY INVISIBLE (-3365 4435);
FORCEPROP 1 LASTPIN (-3375 4425) BN 28
J 0
(-3387 4433);
DISPLAY 0.489362 (-3387 4433);
PAINT GREEN (-3387 4433);
FORCEPROP 2 LAST CDS_LIB mstr_standard
J 0
(-3325 4425);
DISPLAY 0.723404 (-3325 4425);
PAINT MONO (-3325 4425);
DISPLAY INVISIBLE (-3325 4425);
FORCEPROP 1 LAST BODY_TYPE PLUMBING
J 0
(-3325 4475);
DISPLAY 0.872340 (-3325 4475);
PAINT GREEN (-3325 4475);
DISPLAY INVISIBLE (-3325 4475);
FORCEPROP 1 LAST HDL_TAP TRUE
J 0
(-3000 4300);
DISPLAY 0.872340 (-3000 4300);
DISPLAY INVISIBLE (-3000 4300);
FORCEPROP 1 LAST PATH I188
J 0
(-3327 4425);
DISPLAY 0.872340 (-3327 4425);
PAINT GREEN (-3327 4425);
DISPLAY INVISIBLE (-3327 4425);
FORCEADD TAP..1
(-3325 4375);
FORCEPROP 3 LASTPIN (-3375 4375) SIG_NAME M_H_CPU0_SA_DQ<29>
J 0
(-3365 4385);
DISPLAY 0.659574 (-3365 4385);
PAINT MONO (-3365 4385);
DISPLAY INVISIBLE (-3365 4385);
FORCEPROP 1 LASTPIN (-3375 4375) BN 29
J 0
(-3387 4383);
DISPLAY 0.489362 (-3387 4383);
PAINT GREEN (-3387 4383);
FORCEPROP 2 LAST CDS_LIB mstr_standard
J 0
(-3325 4375);
DISPLAY 0.723404 (-3325 4375);
PAINT MONO (-3325 4375);
DISPLAY INVISIBLE (-3325 4375);
FORCEPROP 1 LAST BODY_TYPE PLUMBING
J 0
(-3325 4425);
DISPLAY 0.872340 (-3325 4425);
PAINT GREEN (-3325 4425);
DISPLAY INVISIBLE (-3325 4425);
FORCEPROP 1 LAST HDL_TAP TRUE
J 0
(-3000 4250);
DISPLAY 0.872340 (-3000 4250);
DISPLAY INVISIBLE (-3000 4250);
FORCEPROP 1 LAST PATH I189
J 0
(-3327 4375);
DISPLAY 0.872340 (-3327 4375);
PAINT GREEN (-3327 4375);
DISPLAY INVISIBLE (-3327 4375);
FORCEADD TAP..1
(-3325 4575);
FORCEPROP 3 LASTPIN (-3375 4575) SIG_NAME M_H_CPU0_SA_DQ<25>
J 0
(-3365 4585);
DISPLAY 0.659574 (-3365 4585);
PAINT MONO (-3365 4585);
DISPLAY INVISIBLE (-3365 4585);
FORCEPROP 1 LASTPIN (-3375 4575) BN 25
J 0
(-3387 4583);
DISPLAY 0.489362 (-3387 4583);
PAINT GREEN (-3387 4583);
FORCEPROP 2 LAST CDS_LIB mstr_standard
J 0
(-3325 4575);
DISPLAY 0.723404 (-3325 4575);
PAINT MONO (-3325 4575);
DISPLAY INVISIBLE (-3325 4575);
FORCEPROP 1 LAST BODY_TYPE PLUMBING
J 0
(-3325 4625);
DISPLAY 0.872340 (-3325 4625);
PAINT GREEN (-3325 4625);
DISPLAY INVISIBLE (-3325 4625);
FORCEPROP 1 LAST HDL_TAP TRUE
J 0
(-3000 4450);
DISPLAY 0.872340 (-3000 4450);
DISPLAY INVISIBLE (-3000 4450);
FORCEPROP 1 LAST PATH I190
J 0
(-3327 4575);
DISPLAY 0.872340 (-3327 4575);
PAINT GREEN (-3327 4575);
DISPLAY INVISIBLE (-3327 4575);
FORCEADD TAP..1
(-3325 4525);
FORCEPROP 3 LASTPIN (-3375 4525) SIG_NAME M_H_CPU0_SA_DQ<26>
J 0
(-3365 4535);
DISPLAY 0.659574 (-3365 4535);
PAINT MONO (-3365 4535);
DISPLAY INVISIBLE (-3365 4535);
FORCEPROP 1 LASTPIN (-3375 4525) BN 26
J 0
(-3387 4533);
DISPLAY 0.489362 (-3387 4533);
PAINT GREEN (-3387 4533);
FORCEPROP 2 LAST CDS_LIB mstr_standard
J 0
(-3325 4525);
DISPLAY 0.723404 (-3325 4525);
PAINT MONO (-3325 4525);
DISPLAY INVISIBLE (-3325 4525);
FORCEPROP 1 LAST BODY_TYPE PLUMBING
J 0
(-3325 4575);
DISPLAY 0.872340 (-3325 4575);
PAINT GREEN (-3325 4575);
DISPLAY INVISIBLE (-3325 4575);
FORCEPROP 1 LAST HDL_TAP TRUE
J 0
(-3000 4400);
DISPLAY 0.872340 (-3000 4400);
DISPLAY INVISIBLE (-3000 4400);
FORCEPROP 1 LAST PATH I191
J 0
(-3327 4525);
DISPLAY 0.872340 (-3327 4525);
PAINT GREEN (-3327 4525);
DISPLAY INVISIBLE (-3327 4525);
FORCEADD TAP..1
(-3325 4175);
FORCEPROP 3 LASTPIN (-3375 4175) SIG_NAME M_H_CPU0_SB_DQ<0>
J 0
(-3365 4185);
DISPLAY 0.659574 (-3365 4185);
PAINT MONO (-3365 4185);
DISPLAY INVISIBLE (-3365 4185);
FORCEPROP 1 LASTPIN (-3375 4175) BN 0
J 0
(-3387 4183);
DISPLAY 0.489362 (-3387 4183);
PAINT GREEN (-3387 4183);
FORCEPROP 2 LAST CDS_LIB mstr_standard
J 0
(-3325 4175);
DISPLAY 0.723404 (-3325 4175);
PAINT MONO (-3325 4175);
DISPLAY INVISIBLE (-3325 4175);
FORCEPROP 1 LAST BODY_TYPE PLUMBING
J 0
(-3325 4225);
DISPLAY 0.872340 (-3325 4225);
PAINT GREEN (-3325 4225);
DISPLAY INVISIBLE (-3325 4225);
FORCEPROP 1 LAST HDL_TAP TRUE
J 0
(-3000 4050);
DISPLAY 0.872340 (-3000 4050);
DISPLAY INVISIBLE (-3000 4050);
FORCEPROP 1 LAST PATH I192
J 0
(-3327 4175);
DISPLAY 0.872340 (-3327 4175);
PAINT GREEN (-3327 4175);
DISPLAY INVISIBLE (-3327 4175);
FORCEADD TAP..1
(-3325 4125);
FORCEPROP 3 LASTPIN (-3375 4125) SIG_NAME M_H_CPU0_SB_DQ<1>
J 0
(-3365 4135);
DISPLAY 0.659574 (-3365 4135);
PAINT MONO (-3365 4135);
DISPLAY INVISIBLE (-3365 4135);
FORCEPROP 1 LASTPIN (-3375 4125) BN 1
J 0
(-3387 4133);
DISPLAY 0.489362 (-3387 4133);
PAINT GREEN (-3387 4133);
FORCEPROP 2 LAST CDS_LIB mstr_standard
J 0
(-3325 4125);
DISPLAY 0.723404 (-3325 4125);
PAINT MONO (-3325 4125);
DISPLAY INVISIBLE (-3325 4125);
FORCEPROP 1 LAST BODY_TYPE PLUMBING
J 0
(-3325 4175);
DISPLAY 0.872340 (-3325 4175);
PAINT GREEN (-3325 4175);
DISPLAY INVISIBLE (-3325 4175);
FORCEPROP 1 LAST HDL_TAP TRUE
J 0
(-3000 4000);
DISPLAY 0.872340 (-3000 4000);
DISPLAY INVISIBLE (-3000 4000);
FORCEPROP 1 LAST PATH I193
J 0
(-3327 4125);
DISPLAY 0.872340 (-3327 4125);
PAINT GREEN (-3327 4125);
DISPLAY INVISIBLE (-3327 4125);
FORCEADD TAP..1
(-3325 4275);
FORCEPROP 3 LASTPIN (-3375 4275) SIG_NAME M_H_CPU0_SA_DQ<31>
J 0
(-3365 4285);
DISPLAY 0.659574 (-3365 4285);
PAINT MONO (-3365 4285);
DISPLAY INVISIBLE (-3365 4285);
FORCEPROP 1 LASTPIN (-3375 4275) BN 31
J 0
(-3387 4283);
DISPLAY 0.489362 (-3387 4283);
PAINT GREEN (-3387 4283);
FORCEPROP 2 LAST CDS_LIB mstr_standard
J 0
(-3325 4275);
DISPLAY 0.723404 (-3325 4275);
PAINT MONO (-3325 4275);
DISPLAY INVISIBLE (-3325 4275);
FORCEPROP 1 LAST BODY_TYPE PLUMBING
J 0
(-3325 4325);
DISPLAY 0.872340 (-3325 4325);
PAINT GREEN (-3325 4325);
DISPLAY INVISIBLE (-3325 4325);
FORCEPROP 1 LAST HDL_TAP TRUE
J 0
(-3000 4150);
DISPLAY 0.872340 (-3000 4150);
DISPLAY INVISIBLE (-3000 4150);
FORCEPROP 1 LAST PATH I194
J 0
(-3327 4275);
DISPLAY 0.872340 (-3327 4275);
PAINT GREEN (-3327 4275);
DISPLAY INVISIBLE (-3327 4275);
FORCEADD TAP..1
(-3325 4325);
FORCEPROP 3 LASTPIN (-3375 4325) SIG_NAME M_H_CPU0_SA_DQ<30>
J 0
(-3365 4335);
DISPLAY 0.659574 (-3365 4335);
PAINT MONO (-3365 4335);
DISPLAY INVISIBLE (-3365 4335);
FORCEPROP 1 LASTPIN (-3375 4325) BN 30
J 0
(-3387 4333);
DISPLAY 0.489362 (-3387 4333);
PAINT GREEN (-3387 4333);
FORCEPROP 2 LAST CDS_LIB mstr_standard
J 0
(-3325 4325);
DISPLAY 0.723404 (-3325 4325);
PAINT MONO (-3325 4325);
DISPLAY INVISIBLE (-3325 4325);
FORCEPROP 1 LAST BODY_TYPE PLUMBING
J 0
(-3325 4375);
DISPLAY 0.872340 (-3325 4375);
PAINT GREEN (-3325 4375);
DISPLAY INVISIBLE (-3325 4375);
FORCEPROP 1 LAST HDL_TAP TRUE
J 0
(-3000 4200);
DISPLAY 0.872340 (-3000 4200);
DISPLAY INVISIBLE (-3000 4200);
FORCEPROP 1 LAST PATH I195
J 0
(-3327 4325);
DISPLAY 0.872340 (-3327 4325);
PAINT GREEN (-3327 4325);
DISPLAY INVISIBLE (-3327 4325);
FORCEADD OFFPAGE..6
R 2
(-2725 2425);
FORCEPROP 2 LAST $XR0 92 
J 0
(-2511 2425);
DISPLAY 0.638298 (-2511 2425);
PAINT MONO (-2511 2425);
FORCEPROP 2 LAST PATH I196
J 0
(-2500 2475);
DISPLAY 1.021277 (-2500 2475);
DISPLAY INVISIBLE (-2500 2475);
FORCEPROP 1 LAST COMMENT_BODY TRUE
J 2
(-2825 2350);
DISPLAY 0.872340 (-2825 2350);
PAINT GREEN (-2825 2350);
DISPLAY INVISIBLE (-2825 2350);
FORCEPROP 1 LAST OFFPAGE TRUE
J 2
(-3050 2300);
DISPLAY 0.872340 (-3050 2300);
PAINT GREEN (-3050 2300);
DISPLAY INVISIBLE (-3050 2300);
FORCEPROP 2 LAST CDS_LIB mstr_standard
J 2
(-2725 2425);
DISPLAY 0.723404 (-2725 2425);
PAINT MONO (-2725 2425);
DISPLAY INVISIBLE (-2725 2425);
FORCEADD TAP..1
(-3325 4075);
FORCEPROP 3 LASTPIN (-3375 4075) SIG_NAME M_H_CPU0_SB_DQ<2>
J 0
(-3365 4085);
DISPLAY 0.659574 (-3365 4085);
PAINT MONO (-3365 4085);
DISPLAY INVISIBLE (-3365 4085);
FORCEPROP 1 LASTPIN (-3375 4075) BN 2
J 0
(-3387 4083);
DISPLAY 0.489362 (-3387 4083);
PAINT GREEN (-3387 4083);
FORCEPROP 2 LAST CDS_LIB mstr_standard
J 0
(-3325 4075);
DISPLAY 0.723404 (-3325 4075);
PAINT MONO (-3325 4075);
DISPLAY INVISIBLE (-3325 4075);
FORCEPROP 1 LAST BODY_TYPE PLUMBING
J 0
(-3325 4125);
DISPLAY 0.872340 (-3325 4125);
PAINT GREEN (-3325 4125);
DISPLAY INVISIBLE (-3325 4125);
FORCEPROP 1 LAST HDL_TAP TRUE
J 0
(-3000 3950);
DISPLAY 0.872340 (-3000 3950);
DISPLAY INVISIBLE (-3000 3950);
FORCEPROP 1 LAST PATH I197
J 0
(-3327 4075);
DISPLAY 0.872340 (-3327 4075);
PAINT GREEN (-3327 4075);
DISPLAY INVISIBLE (-3327 4075);
FORCEADD TAP..1
(-3325 4025);
FORCEPROP 3 LASTPIN (-3375 4025) SIG_NAME M_H_CPU0_SB_DQ<3>
J 0
(-3365 4035);
DISPLAY 0.659574 (-3365 4035);
PAINT MONO (-3365 4035);
DISPLAY INVISIBLE (-3365 4035);
FORCEPROP 1 LASTPIN (-3375 4025) BN 3
J 0
(-3387 4033);
DISPLAY 0.489362 (-3387 4033);
PAINT GREEN (-3387 4033);
FORCEPROP 2 LAST CDS_LIB mstr_standard
J 0
(-3325 4025);
DISPLAY 0.723404 (-3325 4025);
PAINT MONO (-3325 4025);
DISPLAY INVISIBLE (-3325 4025);
FORCEPROP 1 LAST BODY_TYPE PLUMBING
J 0
(-3325 4075);
DISPLAY 0.872340 (-3325 4075);
PAINT GREEN (-3325 4075);
DISPLAY INVISIBLE (-3325 4075);
FORCEPROP 1 LAST HDL_TAP TRUE
J 0
(-3000 3900);
DISPLAY 0.872340 (-3000 3900);
DISPLAY INVISIBLE (-3000 3900);
FORCEPROP 1 LAST PATH I198
J 0
(-3327 4025);
DISPLAY 0.872340 (-3327 4025);
PAINT GREEN (-3327 4025);
DISPLAY INVISIBLE (-3327 4025);
FORCEADD TAP..1
(-3325 3975);
FORCEPROP 3 LASTPIN (-3375 3975) SIG_NAME M_H_CPU0_SB_DQ<4>
J 0
(-3365 3985);
DISPLAY 0.659574 (-3365 3985);
PAINT MONO (-3365 3985);
DISPLAY INVISIBLE (-3365 3985);
FORCEPROP 1 LASTPIN (-3375 3975) BN 4
J 0
(-3387 3983);
DISPLAY 0.489362 (-3387 3983);
PAINT GREEN (-3387 3983);
FORCEPROP 2 LAST CDS_LIB mstr_standard
J 0
(-3325 3975);
DISPLAY 0.723404 (-3325 3975);
PAINT MONO (-3325 3975);
DISPLAY INVISIBLE (-3325 3975);
FORCEPROP 1 LAST BODY_TYPE PLUMBING
J 0
(-3325 4025);
DISPLAY 0.872340 (-3325 4025);
PAINT GREEN (-3325 4025);
DISPLAY INVISIBLE (-3325 4025);
FORCEPROP 1 LAST HDL_TAP TRUE
J 0
(-3000 3850);
DISPLAY 0.872340 (-3000 3850);
DISPLAY INVISIBLE (-3000 3850);
FORCEPROP 1 LAST PATH I199
J 0
(-3327 3975);
DISPLAY 0.872340 (-3327 3975);
PAINT GREEN (-3327 3975);
DISPLAY INVISIBLE (-3327 3975);
FORCEADD TAP..1
(-3325 3875);
FORCEPROP 3 LASTPIN (-3375 3875) SIG_NAME M_H_CPU0_SB_DQ<6>
J 0
(-3365 3885);
DISPLAY 0.659574 (-3365 3885);
PAINT MONO (-3365 3885);
DISPLAY INVISIBLE (-3365 3885);
FORCEPROP 1 LASTPIN (-3375 3875) BN 6
J 0
(-3387 3883);
DISPLAY 0.489362 (-3387 3883);
PAINT GREEN (-3387 3883);
FORCEPROP 2 LAST CDS_LIB mstr_standard
J 0
(-3325 3875);
DISPLAY 0.723404 (-3325 3875);
PAINT MONO (-3325 3875);
DISPLAY INVISIBLE (-3325 3875);
FORCEPROP 1 LAST BODY_TYPE PLUMBING
J 0
(-3325 3925);
DISPLAY 0.872340 (-3325 3925);
PAINT GREEN (-3325 3925);
DISPLAY INVISIBLE (-3325 3925);
FORCEPROP 1 LAST HDL_TAP TRUE
J 0
(-3000 3750);
DISPLAY 0.872340 (-3000 3750);
DISPLAY INVISIBLE (-3000 3750);
FORCEPROP 1 LAST PATH I200
J 0
(-3327 3875);
DISPLAY 0.872340 (-3327 3875);
PAINT GREEN (-3327 3875);
DISPLAY INVISIBLE (-3327 3875);
FORCEADD TAP..1
(-3325 3925);
FORCEPROP 3 LASTPIN (-3375 3925) SIG_NAME M_H_CPU0_SB_DQ<5>
J 0
(-3365 3935);
DISPLAY 0.659574 (-3365 3935);
PAINT MONO (-3365 3935);
DISPLAY INVISIBLE (-3365 3935);
FORCEPROP 1 LASTPIN (-3375 3925) BN 5
J 0
(-3387 3933);
DISPLAY 0.489362 (-3387 3933);
PAINT GREEN (-3387 3933);
FORCEPROP 2 LAST CDS_LIB mstr_standard
J 0
(-3325 3925);
DISPLAY 0.723404 (-3325 3925);
PAINT MONO (-3325 3925);
DISPLAY INVISIBLE (-3325 3925);
FORCEPROP 1 LAST BODY_TYPE PLUMBING
J 0
(-3325 3975);
DISPLAY 0.872340 (-3325 3975);
PAINT GREEN (-3325 3975);
DISPLAY INVISIBLE (-3325 3975);
FORCEPROP 1 LAST HDL_TAP TRUE
J 0
(-3000 3800);
DISPLAY 0.872340 (-3000 3800);
DISPLAY INVISIBLE (-3000 3800);
FORCEPROP 1 LAST PATH I201
J 0
(-3327 3925);
DISPLAY 0.872340 (-3327 3925);
PAINT GREEN (-3327 3925);
DISPLAY INVISIBLE (-3327 3925);
FORCEADD TAP..1
(-3325 3675);
FORCEPROP 3 LASTPIN (-3375 3675) SIG_NAME M_H_CPU0_SB_DQ<9>
J 0
(-3365 3685);
DISPLAY 0.659574 (-3365 3685);
PAINT MONO (-3365 3685);
DISPLAY INVISIBLE (-3365 3685);
FORCEPROP 1 LASTPIN (-3375 3675) BN 9
J 0
(-3387 3683);
DISPLAY 0.489362 (-3387 3683);
PAINT GREEN (-3387 3683);
FORCEPROP 2 LAST CDS_LIB mstr_standard
J 0
(-3325 3675);
DISPLAY 0.723404 (-3325 3675);
PAINT MONO (-3325 3675);
DISPLAY INVISIBLE (-3325 3675);
FORCEPROP 1 LAST BODY_TYPE PLUMBING
J 0
(-3325 3725);
DISPLAY 0.872340 (-3325 3725);
PAINT GREEN (-3325 3725);
DISPLAY INVISIBLE (-3325 3725);
FORCEPROP 1 LAST HDL_TAP TRUE
J 0
(-3000 3550);
DISPLAY 0.872340 (-3000 3550);
DISPLAY INVISIBLE (-3000 3550);
FORCEPROP 1 LAST PATH I202
J 0
(-3327 3675);
DISPLAY 0.872340 (-3327 3675);
PAINT GREEN (-3327 3675);
DISPLAY INVISIBLE (-3327 3675);
FORCEADD TAP..1
(-3325 3725);
FORCEPROP 3 LASTPIN (-3375 3725) SIG_NAME M_H_CPU0_SB_DQ<8>
J 0
(-3365 3735);
DISPLAY 0.659574 (-3365 3735);
PAINT MONO (-3365 3735);
DISPLAY INVISIBLE (-3365 3735);
FORCEPROP 1 LASTPIN (-3375 3725) BN 8
J 0
(-3387 3733);
DISPLAY 0.489362 (-3387 3733);
PAINT GREEN (-3387 3733);
FORCEPROP 2 LAST CDS_LIB mstr_standard
J 0
(-3325 3725);
DISPLAY 0.723404 (-3325 3725);
PAINT MONO (-3325 3725);
DISPLAY INVISIBLE (-3325 3725);
FORCEPROP 1 LAST BODY_TYPE PLUMBING
J 0
(-3325 3775);
DISPLAY 0.872340 (-3325 3775);
PAINT GREEN (-3325 3775);
DISPLAY INVISIBLE (-3325 3775);
FORCEPROP 1 LAST HDL_TAP TRUE
J 0
(-3000 3600);
DISPLAY 0.872340 (-3000 3600);
DISPLAY INVISIBLE (-3000 3600);
FORCEPROP 1 LAST PATH I203
J 0
(-3327 3725);
DISPLAY 0.872340 (-3327 3725);
PAINT GREEN (-3327 3725);
DISPLAY INVISIBLE (-3327 3725);
FORCEADD TAP..1
(-3325 3825);
FORCEPROP 3 LASTPIN (-3375 3825) SIG_NAME M_H_CPU0_SB_DQ<7>
J 0
(-3365 3835);
DISPLAY 0.659574 (-3365 3835);
PAINT MONO (-3365 3835);
DISPLAY INVISIBLE (-3365 3835);
FORCEPROP 1 LASTPIN (-3375 3825) BN 7
J 0
(-3387 3833);
DISPLAY 0.489362 (-3387 3833);
PAINT GREEN (-3387 3833);
FORCEPROP 2 LAST CDS_LIB mstr_standard
J 0
(-3325 3825);
DISPLAY 0.723404 (-3325 3825);
PAINT MONO (-3325 3825);
DISPLAY INVISIBLE (-3325 3825);
FORCEPROP 1 LAST BODY_TYPE PLUMBING
J 0
(-3325 3875);
DISPLAY 0.872340 (-3325 3875);
PAINT GREEN (-3325 3875);
DISPLAY INVISIBLE (-3325 3875);
FORCEPROP 1 LAST HDL_TAP TRUE
J 0
(-3000 3700);
DISPLAY 0.872340 (-3000 3700);
DISPLAY INVISIBLE (-3000 3700);
FORCEPROP 1 LAST PATH I204
J 0
(-3327 3825);
DISPLAY 0.872340 (-3327 3825);
PAINT GREEN (-3327 3825);
DISPLAY INVISIBLE (-3327 3825);
FORCEADD TAP..1
(-3325 3625);
FORCEPROP 3 LASTPIN (-3375 3625) SIG_NAME M_H_CPU0_SB_DQ<10>
J 0
(-3365 3635);
DISPLAY 0.659574 (-3365 3635);
PAINT MONO (-3365 3635);
DISPLAY INVISIBLE (-3365 3635);
FORCEPROP 1 LASTPIN (-3375 3625) BN 10
J 0
(-3387 3633);
DISPLAY 0.489362 (-3387 3633);
PAINT GREEN (-3387 3633);
FORCEPROP 2 LAST CDS_LIB mstr_standard
J 0
(-3325 3625);
DISPLAY 0.723404 (-3325 3625);
PAINT MONO (-3325 3625);
DISPLAY INVISIBLE (-3325 3625);
FORCEPROP 1 LAST BODY_TYPE PLUMBING
J 0
(-3325 3675);
DISPLAY 0.872340 (-3325 3675);
PAINT GREEN (-3325 3675);
DISPLAY INVISIBLE (-3325 3675);
FORCEPROP 1 LAST HDL_TAP TRUE
J 0
(-3000 3500);
DISPLAY 0.872340 (-3000 3500);
DISPLAY INVISIBLE (-3000 3500);
FORCEPROP 1 LAST PATH I205
J 0
(-3327 3625);
DISPLAY 0.872340 (-3327 3625);
PAINT GREEN (-3327 3625);
DISPLAY INVISIBLE (-3327 3625);
FORCEADD TAP..1
(-3325 3375);
FORCEPROP 3 LASTPIN (-3375 3375) SIG_NAME M_H_CPU0_SB_DQ<15>
J 0
(-3365 3385);
DISPLAY 0.659574 (-3365 3385);
PAINT MONO (-3365 3385);
DISPLAY INVISIBLE (-3365 3385);
FORCEPROP 1 LASTPIN (-3375 3375) BN 15
J 0
(-3387 3383);
DISPLAY 0.489362 (-3387 3383);
PAINT GREEN (-3387 3383);
FORCEPROP 2 LAST CDS_LIB mstr_standard
J 0
(-3325 3375);
DISPLAY 0.723404 (-3325 3375);
PAINT MONO (-3325 3375);
DISPLAY INVISIBLE (-3325 3375);
FORCEPROP 1 LAST BODY_TYPE PLUMBING
J 0
(-3325 3425);
DISPLAY 0.872340 (-3325 3425);
PAINT GREEN (-3325 3425);
DISPLAY INVISIBLE (-3325 3425);
FORCEPROP 1 LAST HDL_TAP TRUE
J 0
(-3000 3250);
DISPLAY 0.872340 (-3000 3250);
DISPLAY INVISIBLE (-3000 3250);
FORCEPROP 1 LAST PATH I206
J 0
(-3327 3375);
DISPLAY 0.872340 (-3327 3375);
PAINT GREEN (-3327 3375);
DISPLAY INVISIBLE (-3327 3375);
FORCEADD TAP..1
(-3325 3425);
FORCEPROP 3 LASTPIN (-3375 3425) SIG_NAME M_H_CPU0_SB_DQ<14>
J 0
(-3365 3435);
DISPLAY 0.659574 (-3365 3435);
PAINT MONO (-3365 3435);
DISPLAY INVISIBLE (-3365 3435);
FORCEPROP 1 LASTPIN (-3375 3425) BN 14
J 0
(-3387 3433);
DISPLAY 0.489362 (-3387 3433);
PAINT GREEN (-3387 3433);
FORCEPROP 2 LAST CDS_LIB mstr_standard
J 0
(-3325 3425);
DISPLAY 0.723404 (-3325 3425);
PAINT MONO (-3325 3425);
DISPLAY INVISIBLE (-3325 3425);
FORCEPROP 1 LAST BODY_TYPE PLUMBING
J 0
(-3325 3475);
DISPLAY 0.872340 (-3325 3475);
PAINT GREEN (-3325 3475);
DISPLAY INVISIBLE (-3325 3475);
FORCEPROP 1 LAST HDL_TAP TRUE
J 0
(-3000 3300);
DISPLAY 0.872340 (-3000 3300);
DISPLAY INVISIBLE (-3000 3300);
FORCEPROP 1 LAST PATH I207
J 0
(-3327 3425);
DISPLAY 0.872340 (-3327 3425);
PAINT GREEN (-3327 3425);
DISPLAY INVISIBLE (-3327 3425);
FORCEADD TAP..1
(-3325 3475);
FORCEPROP 3 LASTPIN (-3375 3475) SIG_NAME M_H_CPU0_SB_DQ<13>
J 0
(-3365 3485);
DISPLAY 0.659574 (-3365 3485);
PAINT MONO (-3365 3485);
DISPLAY INVISIBLE (-3365 3485);
FORCEPROP 1 LASTPIN (-3375 3475) BN 13
J 0
(-3387 3483);
DISPLAY 0.489362 (-3387 3483);
PAINT GREEN (-3387 3483);
FORCEPROP 2 LAST CDS_LIB mstr_standard
J 0
(-3325 3475);
DISPLAY 0.723404 (-3325 3475);
PAINT MONO (-3325 3475);
DISPLAY INVISIBLE (-3325 3475);
FORCEPROP 1 LAST BODY_TYPE PLUMBING
J 0
(-3325 3525);
DISPLAY 0.872340 (-3325 3525);
PAINT GREEN (-3325 3525);
DISPLAY INVISIBLE (-3325 3525);
FORCEPROP 1 LAST HDL_TAP TRUE
J 0
(-3000 3350);
DISPLAY 0.872340 (-3000 3350);
DISPLAY INVISIBLE (-3000 3350);
FORCEPROP 1 LAST PATH I208
J 0
(-3327 3475);
DISPLAY 0.872340 (-3327 3475);
PAINT GREEN (-3327 3475);
DISPLAY INVISIBLE (-3327 3475);
FORCEADD TAP..1
(-3325 3525);
FORCEPROP 3 LASTPIN (-3375 3525) SIG_NAME M_H_CPU0_SB_DQ<12>
J 0
(-3365 3535);
DISPLAY 0.659574 (-3365 3535);
PAINT MONO (-3365 3535);
DISPLAY INVISIBLE (-3365 3535);
FORCEPROP 1 LASTPIN (-3375 3525) BN 12
J 0
(-3387 3533);
DISPLAY 0.489362 (-3387 3533);
PAINT GREEN (-3387 3533);
FORCEPROP 2 LAST CDS_LIB mstr_standard
J 0
(-3325 3525);
DISPLAY 0.723404 (-3325 3525);
PAINT MONO (-3325 3525);
DISPLAY INVISIBLE (-3325 3525);
FORCEPROP 1 LAST BODY_TYPE PLUMBING
J 0
(-3325 3575);
DISPLAY 0.872340 (-3325 3575);
PAINT GREEN (-3325 3575);
DISPLAY INVISIBLE (-3325 3575);
FORCEPROP 1 LAST HDL_TAP TRUE
J 0
(-3000 3400);
DISPLAY 0.872340 (-3000 3400);
DISPLAY INVISIBLE (-3000 3400);
FORCEPROP 1 LAST PATH I209
J 0
(-3327 3525);
DISPLAY 0.872340 (-3327 3525);
PAINT GREEN (-3327 3525);
DISPLAY INVISIBLE (-3327 3525);
FORCEADD TAP..1
(-3325 3575);
FORCEPROP 3 LASTPIN (-3375 3575) SIG_NAME M_H_CPU0_SB_DQ<11>
J 0
(-3365 3585);
DISPLAY 0.659574 (-3365 3585);
PAINT MONO (-3365 3585);
DISPLAY INVISIBLE (-3365 3585);
FORCEPROP 1 LASTPIN (-3375 3575) BN 11
J 0
(-3387 3583);
DISPLAY 0.489362 (-3387 3583);
PAINT GREEN (-3387 3583);
FORCEPROP 2 LAST CDS_LIB mstr_standard
J 0
(-3325 3575);
DISPLAY 0.723404 (-3325 3575);
PAINT MONO (-3325 3575);
DISPLAY INVISIBLE (-3325 3575);
FORCEPROP 1 LAST BODY_TYPE PLUMBING
J 0
(-3325 3625);
DISPLAY 0.872340 (-3325 3625);
PAINT GREEN (-3325 3625);
DISPLAY INVISIBLE (-3325 3625);
FORCEPROP 1 LAST HDL_TAP TRUE
J 0
(-3000 3450);
DISPLAY 0.872340 (-3000 3450);
DISPLAY INVISIBLE (-3000 3450);
FORCEPROP 1 LAST PATH I210
J 0
(-3327 3575);
DISPLAY 0.872340 (-3327 3575);
PAINT GREEN (-3327 3575);
DISPLAY INVISIBLE (-3327 3575);
FORCEADD TAP..1
(-3325 3175);
FORCEPROP 3 LASTPIN (-3375 3175) SIG_NAME M_H_CPU0_SB_DQ<18>
J 0
(-3365 3185);
DISPLAY 0.659574 (-3365 3185);
PAINT MONO (-3365 3185);
DISPLAY INVISIBLE (-3365 3185);
FORCEPROP 1 LASTPIN (-3375 3175) BN 18
J 0
(-3387 3183);
DISPLAY 0.489362 (-3387 3183);
PAINT GREEN (-3387 3183);
FORCEPROP 2 LAST CDS_LIB mstr_standard
J 0
(-3325 3175);
DISPLAY 0.723404 (-3325 3175);
PAINT MONO (-3325 3175);
DISPLAY INVISIBLE (-3325 3175);
FORCEPROP 1 LAST BODY_TYPE PLUMBING
J 0
(-3325 3225);
DISPLAY 0.872340 (-3325 3225);
PAINT GREEN (-3325 3225);
DISPLAY INVISIBLE (-3325 3225);
FORCEPROP 1 LAST HDL_TAP TRUE
J 0
(-3000 3050);
DISPLAY 0.872340 (-3000 3050);
DISPLAY INVISIBLE (-3000 3050);
FORCEPROP 1 LAST PATH I211
J 0
(-3327 3175);
DISPLAY 0.872340 (-3327 3175);
PAINT GREEN (-3327 3175);
DISPLAY INVISIBLE (-3327 3175);
FORCEADD TAP..1
(-3325 3125);
FORCEPROP 3 LASTPIN (-3375 3125) SIG_NAME M_H_CPU0_SB_DQ<19>
J 0
(-3365 3135);
DISPLAY 0.659574 (-3365 3135);
PAINT MONO (-3365 3135);
DISPLAY INVISIBLE (-3365 3135);
FORCEPROP 1 LASTPIN (-3375 3125) BN 19
J 0
(-3387 3133);
DISPLAY 0.489362 (-3387 3133);
PAINT GREEN (-3387 3133);
FORCEPROP 2 LAST CDS_LIB mstr_standard
J 0
(-3325 3125);
DISPLAY 0.723404 (-3325 3125);
PAINT MONO (-3325 3125);
DISPLAY INVISIBLE (-3325 3125);
FORCEPROP 1 LAST BODY_TYPE PLUMBING
J 0
(-3325 3175);
DISPLAY 0.872340 (-3325 3175);
PAINT GREEN (-3325 3175);
DISPLAY INVISIBLE (-3325 3175);
FORCEPROP 1 LAST HDL_TAP TRUE
J 0
(-3000 3000);
DISPLAY 0.872340 (-3000 3000);
DISPLAY INVISIBLE (-3000 3000);
FORCEPROP 1 LAST PATH I212
J 0
(-3327 3125);
DISPLAY 0.872340 (-3327 3125);
PAINT GREEN (-3327 3125);
DISPLAY INVISIBLE (-3327 3125);
FORCEADD TAP..1
(-3325 3075);
FORCEPROP 3 LASTPIN (-3375 3075) SIG_NAME M_H_CPU0_SB_DQ<20>
J 0
(-3365 3085);
DISPLAY 0.659574 (-3365 3085);
PAINT MONO (-3365 3085);
DISPLAY INVISIBLE (-3365 3085);
FORCEPROP 1 LASTPIN (-3375 3075) BN 20
J 0
(-3387 3083);
DISPLAY 0.489362 (-3387 3083);
PAINT GREEN (-3387 3083);
FORCEPROP 2 LAST CDS_LIB mstr_standard
J 0
(-3325 3075);
DISPLAY 0.723404 (-3325 3075);
PAINT MONO (-3325 3075);
DISPLAY INVISIBLE (-3325 3075);
FORCEPROP 1 LAST BODY_TYPE PLUMBING
J 0
(-3325 3125);
DISPLAY 0.872340 (-3325 3125);
PAINT GREEN (-3325 3125);
DISPLAY INVISIBLE (-3325 3125);
FORCEPROP 1 LAST HDL_TAP TRUE
J 0
(-3000 2950);
DISPLAY 0.872340 (-3000 2950);
DISPLAY INVISIBLE (-3000 2950);
FORCEPROP 1 LAST PATH I213
J 0
(-3327 3075);
DISPLAY 0.872340 (-3327 3075);
PAINT GREEN (-3327 3075);
DISPLAY INVISIBLE (-3327 3075);
FORCEADD TAP..1
(-3325 3275);
FORCEPROP 3 LASTPIN (-3375 3275) SIG_NAME M_H_CPU0_SB_DQ<16>
J 0
(-3365 3285);
DISPLAY 0.659574 (-3365 3285);
PAINT MONO (-3365 3285);
DISPLAY INVISIBLE (-3365 3285);
FORCEPROP 1 LASTPIN (-3375 3275) BN 16
J 0
(-3387 3283);
DISPLAY 0.489362 (-3387 3283);
PAINT GREEN (-3387 3283);
FORCEPROP 2 LAST CDS_LIB mstr_standard
J 0
(-3325 3275);
DISPLAY 0.723404 (-3325 3275);
PAINT MONO (-3325 3275);
DISPLAY INVISIBLE (-3325 3275);
FORCEPROP 1 LAST BODY_TYPE PLUMBING
J 0
(-3325 3325);
DISPLAY 0.872340 (-3325 3325);
PAINT GREEN (-3325 3325);
DISPLAY INVISIBLE (-3325 3325);
FORCEPROP 1 LAST HDL_TAP TRUE
J 0
(-3000 3150);
DISPLAY 0.872340 (-3000 3150);
DISPLAY INVISIBLE (-3000 3150);
FORCEPROP 1 LAST PATH I214
J 0
(-3327 3275);
DISPLAY 0.872340 (-3327 3275);
PAINT GREEN (-3327 3275);
DISPLAY INVISIBLE (-3327 3275);
FORCEADD TAP..1
(-3325 3225);
FORCEPROP 3 LASTPIN (-3375 3225) SIG_NAME M_H_CPU0_SB_DQ<17>
J 0
(-3365 3235);
DISPLAY 0.659574 (-3365 3235);
PAINT MONO (-3365 3235);
DISPLAY INVISIBLE (-3365 3235);
FORCEPROP 1 LASTPIN (-3375 3225) BN 17
J 0
(-3387 3233);
DISPLAY 0.489362 (-3387 3233);
PAINT GREEN (-3387 3233);
FORCEPROP 2 LAST CDS_LIB mstr_standard
J 0
(-3325 3225);
DISPLAY 0.723404 (-3325 3225);
PAINT MONO (-3325 3225);
DISPLAY INVISIBLE (-3325 3225);
FORCEPROP 1 LAST BODY_TYPE PLUMBING
J 0
(-3325 3275);
DISPLAY 0.872340 (-3325 3275);
PAINT GREEN (-3325 3275);
DISPLAY INVISIBLE (-3325 3275);
FORCEPROP 1 LAST HDL_TAP TRUE
J 0
(-3000 3100);
DISPLAY 0.872340 (-3000 3100);
DISPLAY INVISIBLE (-3000 3100);
FORCEPROP 1 LAST PATH I215
J 0
(-3327 3225);
DISPLAY 0.872340 (-3327 3225);
PAINT GREEN (-3327 3225);
DISPLAY INVISIBLE (-3327 3225);
FORCEADD TAP..1
(-3325 2975);
FORCEPROP 3 LASTPIN (-3375 2975) SIG_NAME M_H_CPU0_SB_DQ<22>
J 0
(-3365 2985);
DISPLAY 0.659574 (-3365 2985);
PAINT MONO (-3365 2985);
DISPLAY INVISIBLE (-3365 2985);
FORCEPROP 1 LASTPIN (-3375 2975) BN 22
J 0
(-3387 2983);
DISPLAY 0.489362 (-3387 2983);
PAINT GREEN (-3387 2983);
FORCEPROP 2 LAST CDS_LIB mstr_standard
J 0
(-3325 2975);
DISPLAY 0.723404 (-3325 2975);
PAINT MONO (-3325 2975);
DISPLAY INVISIBLE (-3325 2975);
FORCEPROP 1 LAST BODY_TYPE PLUMBING
J 0
(-3325 3025);
DISPLAY 0.872340 (-3325 3025);
PAINT GREEN (-3325 3025);
DISPLAY INVISIBLE (-3325 3025);
FORCEPROP 1 LAST HDL_TAP TRUE
J 0
(-3000 2850);
DISPLAY 0.872340 (-3000 2850);
DISPLAY INVISIBLE (-3000 2850);
FORCEPROP 1 LAST PATH I216
J 0
(-3327 2975);
DISPLAY 0.872340 (-3327 2975);
PAINT GREEN (-3327 2975);
DISPLAY INVISIBLE (-3327 2975);
FORCEADD TAP..1
(-3325 2925);
FORCEPROP 3 LASTPIN (-3375 2925) SIG_NAME M_H_CPU0_SB_DQ<23>
J 0
(-3365 2935);
DISPLAY 0.659574 (-3365 2935);
PAINT MONO (-3365 2935);
DISPLAY INVISIBLE (-3365 2935);
FORCEPROP 1 LASTPIN (-3375 2925) BN 23
J 0
(-3387 2933);
DISPLAY 0.489362 (-3387 2933);
PAINT GREEN (-3387 2933);
FORCEPROP 2 LAST CDS_LIB mstr_standard
J 0
(-3325 2925);
DISPLAY 0.723404 (-3325 2925);
PAINT MONO (-3325 2925);
DISPLAY INVISIBLE (-3325 2925);
FORCEPROP 1 LAST BODY_TYPE PLUMBING
J 0
(-3325 2975);
DISPLAY 0.872340 (-3325 2975);
PAINT GREEN (-3325 2975);
DISPLAY INVISIBLE (-3325 2975);
FORCEPROP 1 LAST HDL_TAP TRUE
J 0
(-3000 2800);
DISPLAY 0.872340 (-3000 2800);
DISPLAY INVISIBLE (-3000 2800);
FORCEPROP 1 LAST PATH I217
J 0
(-3327 2925);
DISPLAY 0.872340 (-3327 2925);
PAINT GREEN (-3327 2925);
DISPLAY INVISIBLE (-3327 2925);
FORCEADD TAP..1
(-3325 3025);
FORCEPROP 3 LASTPIN (-3375 3025) SIG_NAME M_H_CPU0_SB_DQ<21>
J 0
(-3365 3035);
DISPLAY 0.659574 (-3365 3035);
PAINT MONO (-3365 3035);
DISPLAY INVISIBLE (-3365 3035);
FORCEPROP 1 LASTPIN (-3375 3025) BN 21
J 0
(-3387 3033);
DISPLAY 0.489362 (-3387 3033);
PAINT GREEN (-3387 3033);
FORCEPROP 2 LAST CDS_LIB mstr_standard
J 0
(-3325 3025);
DISPLAY 0.723404 (-3325 3025);
PAINT MONO (-3325 3025);
DISPLAY INVISIBLE (-3325 3025);
FORCEPROP 1 LAST BODY_TYPE PLUMBING
J 0
(-3325 3075);
DISPLAY 0.872340 (-3325 3075);
PAINT GREEN (-3325 3075);
DISPLAY INVISIBLE (-3325 3075);
FORCEPROP 1 LAST HDL_TAP TRUE
J 0
(-3000 2900);
DISPLAY 0.872340 (-3000 2900);
DISPLAY INVISIBLE (-3000 2900);
FORCEPROP 1 LAST PATH I218
J 0
(-3327 3025);
DISPLAY 0.872340 (-3327 3025);
PAINT GREEN (-3327 3025);
DISPLAY INVISIBLE (-3327 3025);
FORCEADD TAP..1
(-3325 2825);
FORCEPROP 3 LASTPIN (-3375 2825) SIG_NAME M_H_CPU0_SB_DQ<24>
J 0
(-3365 2835);
DISPLAY 0.659574 (-3365 2835);
PAINT MONO (-3365 2835);
DISPLAY INVISIBLE (-3365 2835);
FORCEPROP 1 LASTPIN (-3375 2825) BN 24
J 0
(-3387 2833);
DISPLAY 0.489362 (-3387 2833);
PAINT GREEN (-3387 2833);
FORCEPROP 2 LAST CDS_LIB mstr_standard
J 0
(-3325 2825);
DISPLAY 0.723404 (-3325 2825);
PAINT MONO (-3325 2825);
DISPLAY INVISIBLE (-3325 2825);
FORCEPROP 1 LAST BODY_TYPE PLUMBING
J 0
(-3325 2875);
DISPLAY 0.872340 (-3325 2875);
PAINT GREEN (-3325 2875);
DISPLAY INVISIBLE (-3325 2875);
FORCEPROP 1 LAST HDL_TAP TRUE
J 0
(-3000 2700);
DISPLAY 0.872340 (-3000 2700);
DISPLAY INVISIBLE (-3000 2700);
FORCEPROP 1 LAST PATH I219
J 0
(-3327 2825);
DISPLAY 0.872340 (-3327 2825);
PAINT GREEN (-3327 2825);
DISPLAY INVISIBLE (-3327 2825);
FORCEADD TAP..1
(-3325 2675);
FORCEPROP 3 LASTPIN (-3375 2675) SIG_NAME M_H_CPU0_SB_DQ<27>
J 0
(-3365 2685);
DISPLAY 0.659574 (-3365 2685);
PAINT MONO (-3365 2685);
DISPLAY INVISIBLE (-3365 2685);
FORCEPROP 1 LASTPIN (-3375 2675) BN 27
J 0
(-3387 2683);
DISPLAY 0.489362 (-3387 2683);
PAINT GREEN (-3387 2683);
FORCEPROP 2 LAST CDS_LIB mstr_standard
J 0
(-3325 2675);
DISPLAY 0.723404 (-3325 2675);
PAINT MONO (-3325 2675);
DISPLAY INVISIBLE (-3325 2675);
FORCEPROP 1 LAST BODY_TYPE PLUMBING
J 0
(-3325 2725);
DISPLAY 0.872340 (-3325 2725);
PAINT GREEN (-3325 2725);
DISPLAY INVISIBLE (-3325 2725);
FORCEPROP 1 LAST HDL_TAP TRUE
J 0
(-3000 2550);
DISPLAY 0.872340 (-3000 2550);
DISPLAY INVISIBLE (-3000 2550);
FORCEPROP 1 LAST PATH I220
J 0
(-3327 2675);
DISPLAY 0.872340 (-3327 2675);
PAINT GREEN (-3327 2675);
DISPLAY INVISIBLE (-3327 2675);
FORCEADD TAP..1
(-3325 2625);
FORCEPROP 3 LASTPIN (-3375 2625) SIG_NAME M_H_CPU0_SB_DQ<28>
J 0
(-3365 2635);
DISPLAY 0.659574 (-3365 2635);
PAINT MONO (-3365 2635);
DISPLAY INVISIBLE (-3365 2635);
FORCEPROP 1 LASTPIN (-3375 2625) BN 28
J 0
(-3387 2633);
DISPLAY 0.489362 (-3387 2633);
PAINT GREEN (-3387 2633);
FORCEPROP 2 LAST CDS_LIB mstr_standard
J 0
(-3325 2625);
DISPLAY 0.723404 (-3325 2625);
PAINT MONO (-3325 2625);
DISPLAY INVISIBLE (-3325 2625);
FORCEPROP 1 LAST BODY_TYPE PLUMBING
J 0
(-3325 2675);
DISPLAY 0.872340 (-3325 2675);
PAINT GREEN (-3325 2675);
DISPLAY INVISIBLE (-3325 2675);
FORCEPROP 1 LAST HDL_TAP TRUE
J 0
(-3000 2500);
DISPLAY 0.872340 (-3000 2500);
DISPLAY INVISIBLE (-3000 2500);
FORCEPROP 1 LAST PATH I221
J 0
(-3327 2625);
DISPLAY 0.872340 (-3327 2625);
PAINT GREEN (-3327 2625);
DISPLAY INVISIBLE (-3327 2625);
FORCEADD TAP..1
(-3325 2575);
FORCEPROP 3 LASTPIN (-3375 2575) SIG_NAME M_H_CPU0_SB_DQ<29>
J 0
(-3365 2585);
DISPLAY 0.659574 (-3365 2585);
PAINT MONO (-3365 2585);
DISPLAY INVISIBLE (-3365 2585);
FORCEPROP 1 LASTPIN (-3375 2575) BN 29
J 0
(-3387 2583);
DISPLAY 0.489362 (-3387 2583);
PAINT GREEN (-3387 2583);
FORCEPROP 2 LAST CDS_LIB mstr_standard
J 0
(-3325 2575);
DISPLAY 0.723404 (-3325 2575);
PAINT MONO (-3325 2575);
DISPLAY INVISIBLE (-3325 2575);
FORCEPROP 1 LAST BODY_TYPE PLUMBING
J 0
(-3325 2625);
DISPLAY 0.872340 (-3325 2625);
PAINT GREEN (-3325 2625);
DISPLAY INVISIBLE (-3325 2625);
FORCEPROP 1 LAST HDL_TAP TRUE
J 0
(-3000 2450);
DISPLAY 0.872340 (-3000 2450);
DISPLAY INVISIBLE (-3000 2450);
FORCEPROP 1 LAST PATH I222
J 0
(-3327 2575);
DISPLAY 0.872340 (-3327 2575);
PAINT GREEN (-3327 2575);
DISPLAY INVISIBLE (-3327 2575);
FORCEADD TAP..1
(-3325 2775);
FORCEPROP 3 LASTPIN (-3375 2775) SIG_NAME M_H_CPU0_SB_DQ<25>
J 0
(-3365 2785);
DISPLAY 0.659574 (-3365 2785);
PAINT MONO (-3365 2785);
DISPLAY INVISIBLE (-3365 2785);
FORCEPROP 1 LASTPIN (-3375 2775) BN 25
J 0
(-3387 2783);
DISPLAY 0.489362 (-3387 2783);
PAINT GREEN (-3387 2783);
FORCEPROP 2 LAST CDS_LIB mstr_standard
J 0
(-3325 2775);
DISPLAY 0.723404 (-3325 2775);
PAINT MONO (-3325 2775);
DISPLAY INVISIBLE (-3325 2775);
FORCEPROP 1 LAST BODY_TYPE PLUMBING
J 0
(-3325 2825);
DISPLAY 0.872340 (-3325 2825);
PAINT GREEN (-3325 2825);
DISPLAY INVISIBLE (-3325 2825);
FORCEPROP 1 LAST HDL_TAP TRUE
J 0
(-3000 2650);
DISPLAY 0.872340 (-3000 2650);
DISPLAY INVISIBLE (-3000 2650);
FORCEPROP 1 LAST PATH I223
J 0
(-3327 2775);
DISPLAY 0.872340 (-3327 2775);
PAINT GREEN (-3327 2775);
DISPLAY INVISIBLE (-3327 2775);
FORCEADD TAP..1
(-3325 2725);
FORCEPROP 3 LASTPIN (-3375 2725) SIG_NAME M_H_CPU0_SB_DQ<26>
J 0
(-3365 2735);
DISPLAY 0.659574 (-3365 2735);
PAINT MONO (-3365 2735);
DISPLAY INVISIBLE (-3365 2735);
FORCEPROP 1 LASTPIN (-3375 2725) BN 26
J 0
(-3387 2733);
DISPLAY 0.489362 (-3387 2733);
PAINT GREEN (-3387 2733);
FORCEPROP 2 LAST CDS_LIB mstr_standard
J 0
(-3325 2725);
DISPLAY 0.723404 (-3325 2725);
PAINT MONO (-3325 2725);
DISPLAY INVISIBLE (-3325 2725);
FORCEPROP 1 LAST BODY_TYPE PLUMBING
J 0
(-3325 2775);
DISPLAY 0.872340 (-3325 2775);
PAINT GREEN (-3325 2775);
DISPLAY INVISIBLE (-3325 2775);
FORCEPROP 1 LAST HDL_TAP TRUE
J 0
(-3000 2600);
DISPLAY 0.872340 (-3000 2600);
DISPLAY INVISIBLE (-3000 2600);
FORCEPROP 1 LAST PATH I224
J 0
(-3327 2725);
DISPLAY 0.872340 (-3327 2725);
PAINT GREEN (-3327 2725);
DISPLAY INVISIBLE (-3327 2725);
FORCEADD TAP..1
(-3325 2375);
FORCEPROP 3 LASTPIN (-3375 2375) SIG_NAME M_H_CPU0_SA_CB<0>
J 0
(-3365 2385);
DISPLAY 0.659574 (-3365 2385);
PAINT MONO (-3365 2385);
DISPLAY INVISIBLE (-3365 2385);
FORCEPROP 1 LASTPIN (-3375 2375) BN 0
J 0
(-3387 2383);
DISPLAY 0.489362 (-3387 2383);
PAINT GREEN (-3387 2383);
FORCEPROP 2 LAST CDS_LIB mstr_standard
J 2
(-3325 2375);
DISPLAY 0.723404 (-3325 2375);
PAINT MONO (-3325 2375);
DISPLAY INVISIBLE (-3325 2375);
FORCEPROP 1 LAST BODY_TYPE PLUMBING
J 0
(-3325 2425);
DISPLAY 0.872340 (-3325 2425);
PAINT GREEN (-3325 2425);
DISPLAY INVISIBLE (-3325 2425);
FORCEPROP 1 LAST HDL_TAP TRUE
J 0
(-3000 2250);
DISPLAY 0.872340 (-3000 2250);
DISPLAY INVISIBLE (-3000 2250);
FORCEPROP 1 LAST PATH I225
J 0
(-3327 2375);
DISPLAY 0.872340 (-3327 2375);
PAINT GREEN (-3327 2375);
DISPLAY INVISIBLE (-3327 2375);
FORCEADD TAP..1
(-3325 2325);
FORCEPROP 3 LASTPIN (-3375 2325) SIG_NAME M_H_CPU0_SA_CB<1>
J 0
(-3365 2335);
DISPLAY 0.659574 (-3365 2335);
PAINT MONO (-3365 2335);
DISPLAY INVISIBLE (-3365 2335);
FORCEPROP 1 LASTPIN (-3375 2325) BN 1
J 0
(-3387 2333);
DISPLAY 0.489362 (-3387 2333);
PAINT GREEN (-3387 2333);
FORCEPROP 2 LAST CDS_LIB mstr_standard
J 2
(-3325 2325);
DISPLAY 0.723404 (-3325 2325);
PAINT MONO (-3325 2325);
DISPLAY INVISIBLE (-3325 2325);
FORCEPROP 1 LAST BODY_TYPE PLUMBING
J 0
(-3325 2375);
DISPLAY 0.872340 (-3325 2375);
PAINT GREEN (-3325 2375);
DISPLAY INVISIBLE (-3325 2375);
FORCEPROP 1 LAST HDL_TAP TRUE
J 0
(-3000 2200);
DISPLAY 0.872340 (-3000 2200);
DISPLAY INVISIBLE (-3000 2200);
FORCEPROP 1 LAST PATH I226
J 0
(-3327 2325);
DISPLAY 0.872340 (-3327 2325);
PAINT GREEN (-3327 2325);
DISPLAY INVISIBLE (-3327 2325);
FORCEADD TAP..1
(-3325 2525);
FORCEPROP 3 LASTPIN (-3375 2525) SIG_NAME M_H_CPU0_SB_DQ<30>
J 0
(-3365 2535);
DISPLAY 0.659574 (-3365 2535);
PAINT MONO (-3365 2535);
DISPLAY INVISIBLE (-3365 2535);
FORCEPROP 1 LASTPIN (-3375 2525) BN 30
J 0
(-3387 2533);
DISPLAY 0.489362 (-3387 2533);
PAINT GREEN (-3387 2533);
FORCEPROP 2 LAST CDS_LIB mstr_standard
J 0
(-3325 2525);
DISPLAY 0.723404 (-3325 2525);
PAINT MONO (-3325 2525);
DISPLAY INVISIBLE (-3325 2525);
FORCEPROP 1 LAST BODY_TYPE PLUMBING
J 0
(-3325 2575);
DISPLAY 0.872340 (-3325 2575);
PAINT GREEN (-3325 2575);
DISPLAY INVISIBLE (-3325 2575);
FORCEPROP 1 LAST HDL_TAP TRUE
J 0
(-3000 2400);
DISPLAY 0.872340 (-3000 2400);
DISPLAY INVISIBLE (-3000 2400);
FORCEPROP 1 LAST PATH I227
J 0
(-3327 2525);
DISPLAY 0.872340 (-3327 2525);
PAINT GREEN (-3327 2525);
DISPLAY INVISIBLE (-3327 2525);
FORCEADD TAP..1
(-3325 2475);
FORCEPROP 3 LASTPIN (-3375 2475) SIG_NAME M_H_CPU0_SB_DQ<31>
J 0
(-3365 2485);
DISPLAY 0.659574 (-3365 2485);
PAINT MONO (-3365 2485);
DISPLAY INVISIBLE (-3365 2485);
FORCEPROP 1 LASTPIN (-3375 2475) BN 31
J 0
(-3387 2483);
DISPLAY 0.489362 (-3387 2483);
PAINT GREEN (-3387 2483);
FORCEPROP 2 LAST CDS_LIB mstr_standard
J 0
(-3325 2475);
DISPLAY 0.723404 (-3325 2475);
PAINT MONO (-3325 2475);
DISPLAY INVISIBLE (-3325 2475);
FORCEPROP 1 LAST BODY_TYPE PLUMBING
J 0
(-3325 2525);
DISPLAY 0.872340 (-3325 2525);
PAINT GREEN (-3325 2525);
DISPLAY INVISIBLE (-3325 2525);
FORCEPROP 1 LAST HDL_TAP TRUE
J 0
(-3000 2350);
DISPLAY 0.872340 (-3000 2350);
DISPLAY INVISIBLE (-3000 2350);
FORCEPROP 1 LAST PATH I228
J 0
(-3327 2475);
DISPLAY 0.872340 (-3327 2475);
PAINT GREEN (-3327 2475);
DISPLAY INVISIBLE (-3327 2475);
FORCEADD TAP..1
(-3325 2225);
FORCEPROP 3 LASTPIN (-3375 2225) SIG_NAME M_H_CPU0_SA_CB<3>
J 0
(-3365 2235);
DISPLAY 0.659574 (-3365 2235);
PAINT MONO (-3365 2235);
DISPLAY INVISIBLE (-3365 2235);
FORCEPROP 1 LASTPIN (-3375 2225) BN 3
J 0
(-3387 2233);
DISPLAY 0.489362 (-3387 2233);
PAINT GREEN (-3387 2233);
FORCEPROP 2 LAST CDS_LIB mstr_standard
J 2
(-3325 2225);
DISPLAY 0.723404 (-3325 2225);
PAINT MONO (-3325 2225);
DISPLAY INVISIBLE (-3325 2225);
FORCEPROP 1 LAST BODY_TYPE PLUMBING
J 0
(-3325 2275);
DISPLAY 0.872340 (-3325 2275);
PAINT GREEN (-3325 2275);
DISPLAY INVISIBLE (-3325 2275);
FORCEPROP 1 LAST HDL_TAP TRUE
J 0
(-3000 2100);
DISPLAY 0.872340 (-3000 2100);
DISPLAY INVISIBLE (-3000 2100);
FORCEPROP 1 LAST PATH I229
J 0
(-3327 2225);
DISPLAY 0.872340 (-3327 2225);
PAINT GREEN (-3327 2225);
DISPLAY INVISIBLE (-3327 2225);
FORCEADD TAP..1
(-3325 2275);
FORCEPROP 3 LASTPIN (-3375 2275) SIG_NAME M_H_CPU0_SA_CB<2>
J 0
(-3365 2285);
DISPLAY 0.659574 (-3365 2285);
PAINT MONO (-3365 2285);
DISPLAY INVISIBLE (-3365 2285);
FORCEPROP 1 LASTPIN (-3375 2275) BN 2
J 0
(-3387 2283);
DISPLAY 0.489362 (-3387 2283);
PAINT GREEN (-3387 2283);
FORCEPROP 2 LAST CDS_LIB mstr_standard
J 2
(-3325 2275);
DISPLAY 0.723404 (-3325 2275);
PAINT MONO (-3325 2275);
DISPLAY INVISIBLE (-3325 2275);
FORCEPROP 1 LAST BODY_TYPE PLUMBING
J 0
(-3325 2325);
DISPLAY 0.872340 (-3325 2325);
PAINT GREEN (-3325 2325);
DISPLAY INVISIBLE (-3325 2325);
FORCEPROP 1 LAST HDL_TAP TRUE
J 0
(-3000 2150);
DISPLAY 0.872340 (-3000 2150);
DISPLAY INVISIBLE (-3000 2150);
FORCEPROP 1 LAST PATH I230
J 0
(-3327 2275);
DISPLAY 0.872340 (-3327 2275);
PAINT GREEN (-3327 2275);
DISPLAY INVISIBLE (-3327 2275);
FORCEADD TAP..1
(-3325 2075);
FORCEPROP 3 LASTPIN (-3375 2075) SIG_NAME M_H_CPU0_SA_CB<6>
J 0
(-3365 2085);
DISPLAY 0.659574 (-3365 2085);
PAINT MONO (-3365 2085);
DISPLAY INVISIBLE (-3365 2085);
FORCEPROP 1 LASTPIN (-3375 2075) BN 6
J 0
(-3387 2083);
DISPLAY 0.489362 (-3387 2083);
PAINT GREEN (-3387 2083);
FORCEPROP 2 LAST CDS_LIB mstr_standard
J 2
(-3325 2075);
DISPLAY 0.723404 (-3325 2075);
PAINT MONO (-3325 2075);
DISPLAY INVISIBLE (-3325 2075);
FORCEPROP 1 LAST BODY_TYPE PLUMBING
J 0
(-3325 2125);
DISPLAY 0.872340 (-3325 2125);
PAINT GREEN (-3325 2125);
DISPLAY INVISIBLE (-3325 2125);
FORCEPROP 1 LAST HDL_TAP TRUE
J 0
(-3000 1950);
DISPLAY 0.872340 (-3000 1950);
DISPLAY INVISIBLE (-3000 1950);
FORCEPROP 1 LAST PATH I231
J 0
(-3327 2075);
DISPLAY 0.872340 (-3327 2075);
PAINT GREEN (-3327 2075);
DISPLAY INVISIBLE (-3327 2075);
FORCEADD TAP..1
(-3325 2125);
FORCEPROP 3 LASTPIN (-3375 2125) SIG_NAME M_H_CPU0_SA_CB<5>
J 0
(-3365 2135);
DISPLAY 0.659574 (-3365 2135);
PAINT MONO (-3365 2135);
DISPLAY INVISIBLE (-3365 2135);
FORCEPROP 1 LASTPIN (-3375 2125) BN 5
J 0
(-3387 2133);
DISPLAY 0.489362 (-3387 2133);
PAINT GREEN (-3387 2133);
FORCEPROP 2 LAST CDS_LIB mstr_standard
J 2
(-3325 2125);
DISPLAY 0.723404 (-3325 2125);
PAINT MONO (-3325 2125);
DISPLAY INVISIBLE (-3325 2125);
FORCEPROP 1 LAST BODY_TYPE PLUMBING
J 0
(-3325 2175);
DISPLAY 0.872340 (-3325 2175);
PAINT GREEN (-3325 2175);
DISPLAY INVISIBLE (-3325 2175);
FORCEPROP 1 LAST HDL_TAP TRUE
J 0
(-3000 2000);
DISPLAY 0.872340 (-3000 2000);
DISPLAY INVISIBLE (-3000 2000);
FORCEPROP 1 LAST PATH I232
J 0
(-3327 2125);
DISPLAY 0.872340 (-3327 2125);
PAINT GREEN (-3327 2125);
DISPLAY INVISIBLE (-3327 2125);
FORCEADD TAP..1
(-3325 2175);
FORCEPROP 3 LASTPIN (-3375 2175) SIG_NAME M_H_CPU0_SA_CB<4>
J 0
(-3365 2185);
DISPLAY 0.659574 (-3365 2185);
PAINT MONO (-3365 2185);
DISPLAY INVISIBLE (-3365 2185);
FORCEPROP 1 LASTPIN (-3375 2175) BN 4
J 0
(-3387 2183);
DISPLAY 0.489362 (-3387 2183);
PAINT GREEN (-3387 2183);
FORCEPROP 2 LAST CDS_LIB mstr_standard
J 2
(-3325 2175);
DISPLAY 0.723404 (-3325 2175);
PAINT MONO (-3325 2175);
DISPLAY INVISIBLE (-3325 2175);
FORCEPROP 1 LAST BODY_TYPE PLUMBING
J 0
(-3325 2225);
DISPLAY 0.872340 (-3325 2225);
PAINT GREEN (-3325 2225);
DISPLAY INVISIBLE (-3325 2225);
FORCEPROP 1 LAST HDL_TAP TRUE
J 0
(-3000 2050);
DISPLAY 0.872340 (-3000 2050);
DISPLAY INVISIBLE (-3000 2050);
FORCEPROP 1 LAST PATH I233
J 0
(-3327 2175);
DISPLAY 0.872340 (-3327 2175);
PAINT GREEN (-3327 2175);
DISPLAY INVISIBLE (-3327 2175);
FORCEADD OFFPAGE..6
R 2
(-2725 1975);
FORCEPROP 2 LAST $XR0 92 
J 0
(-2511 1975);
DISPLAY 0.638298 (-2511 1975);
PAINT MONO (-2511 1975);
FORCEPROP 2 LAST PATH I234
J 0
(-2500 2025);
DISPLAY 1.021277 (-2500 2025);
DISPLAY INVISIBLE (-2500 2025);
FORCEPROP 1 LAST COMMENT_BODY TRUE
J 2
(-2825 1900);
DISPLAY 0.872340 (-2825 1900);
PAINT GREEN (-2825 1900);
DISPLAY INVISIBLE (-2825 1900);
FORCEPROP 1 LAST OFFPAGE TRUE
J 2
(-3050 1850);
DISPLAY 0.872340 (-3050 1850);
PAINT GREEN (-3050 1850);
DISPLAY INVISIBLE (-3050 1850);
FORCEPROP 2 LAST CDS_LIB mstr_standard
J 2
(-2725 1975);
DISPLAY 0.723404 (-2725 1975);
PAINT MONO (-2725 1975);
DISPLAY INVISIBLE (-2725 1975);
FORCEADD TAP..1
(-3325 1875);
FORCEPROP 3 LASTPIN (-3375 1875) SIG_NAME M_H_CPU0_SB_CB<1>
J 0
(-3365 1885);
DISPLAY 0.659574 (-3365 1885);
PAINT MONO (-3365 1885);
DISPLAY INVISIBLE (-3365 1885);
FORCEPROP 1 LASTPIN (-3375 1875) BN 1
J 0
(-3387 1883);
DISPLAY 0.489362 (-3387 1883);
PAINT GREEN (-3387 1883);
FORCEPROP 2 LAST CDS_LIB mstr_standard
J 2
(-3325 1875);
DISPLAY 0.723404 (-3325 1875);
PAINT MONO (-3325 1875);
DISPLAY INVISIBLE (-3325 1875);
FORCEPROP 1 LAST BODY_TYPE PLUMBING
J 0
(-3325 1925);
DISPLAY 0.872340 (-3325 1925);
PAINT GREEN (-3325 1925);
DISPLAY INVISIBLE (-3325 1925);
FORCEPROP 1 LAST HDL_TAP TRUE
J 0
(-3000 1750);
DISPLAY 0.872340 (-3000 1750);
DISPLAY INVISIBLE (-3000 1750);
FORCEPROP 1 LAST PATH I235
J 0
(-3327 1875);
DISPLAY 0.872340 (-3327 1875);
PAINT GREEN (-3327 1875);
DISPLAY INVISIBLE (-3327 1875);
FORCEADD TAP..1
(-3325 1925);
FORCEPROP 3 LASTPIN (-3375 1925) SIG_NAME M_H_CPU0_SB_CB<0>
J 0
(-3365 1935);
DISPLAY 0.659574 (-3365 1935);
PAINT MONO (-3365 1935);
DISPLAY INVISIBLE (-3365 1935);
FORCEPROP 1 LASTPIN (-3375 1925) BN 0
J 0
(-3387 1933);
DISPLAY 0.489362 (-3387 1933);
PAINT GREEN (-3387 1933);
FORCEPROP 2 LAST CDS_LIB mstr_standard
J 2
(-3325 1925);
DISPLAY 0.723404 (-3325 1925);
PAINT MONO (-3325 1925);
DISPLAY INVISIBLE (-3325 1925);
FORCEPROP 1 LAST BODY_TYPE PLUMBING
J 0
(-3325 1975);
DISPLAY 0.872340 (-3325 1975);
PAINT GREEN (-3325 1975);
DISPLAY INVISIBLE (-3325 1975);
FORCEPROP 1 LAST HDL_TAP TRUE
J 0
(-3000 1800);
DISPLAY 0.872340 (-3000 1800);
DISPLAY INVISIBLE (-3000 1800);
FORCEPROP 1 LAST PATH I236
J 0
(-3327 1925);
DISPLAY 0.872340 (-3327 1925);
PAINT GREEN (-3327 1925);
DISPLAY INVISIBLE (-3327 1925);
FORCEADD TAP..1
(-3325 2025);
FORCEPROP 3 LASTPIN (-3375 2025) SIG_NAME M_H_CPU0_SA_CB<7>
J 0
(-3365 2035);
DISPLAY 0.659574 (-3365 2035);
PAINT MONO (-3365 2035);
DISPLAY INVISIBLE (-3365 2035);
FORCEPROP 1 LASTPIN (-3375 2025) BN 7
J 0
(-3387 2033);
DISPLAY 0.489362 (-3387 2033);
PAINT GREEN (-3387 2033);
FORCEPROP 2 LAST CDS_LIB mstr_standard
J 2
(-3325 2025);
DISPLAY 0.723404 (-3325 2025);
PAINT MONO (-3325 2025);
DISPLAY INVISIBLE (-3325 2025);
FORCEPROP 1 LAST BODY_TYPE PLUMBING
J 0
(-3325 2075);
DISPLAY 0.872340 (-3325 2075);
PAINT GREEN (-3325 2075);
DISPLAY INVISIBLE (-3325 2075);
FORCEPROP 1 LAST HDL_TAP TRUE
J 0
(-3000 1900);
DISPLAY 0.872340 (-3000 1900);
DISPLAY INVISIBLE (-3000 1900);
FORCEPROP 1 LAST PATH I237
J 0
(-3327 2025);
DISPLAY 0.872340 (-3327 2025);
PAINT GREEN (-3327 2025);
DISPLAY INVISIBLE (-3327 2025);
FORCEADD TAP..1
(-3325 1825);
FORCEPROP 3 LASTPIN (-3375 1825) SIG_NAME M_H_CPU0_SB_CB<2>
J 0
(-3365 1835);
DISPLAY 0.659574 (-3365 1835);
PAINT MONO (-3365 1835);
DISPLAY INVISIBLE (-3365 1835);
FORCEPROP 1 LASTPIN (-3375 1825) BN 2
J 0
(-3387 1833);
DISPLAY 0.489362 (-3387 1833);
PAINT GREEN (-3387 1833);
FORCEPROP 2 LAST CDS_LIB mstr_standard
J 2
(-3325 1825);
DISPLAY 0.723404 (-3325 1825);
PAINT MONO (-3325 1825);
DISPLAY INVISIBLE (-3325 1825);
FORCEPROP 1 LAST BODY_TYPE PLUMBING
J 0
(-3325 1875);
DISPLAY 0.872340 (-3325 1875);
PAINT GREEN (-3325 1875);
DISPLAY INVISIBLE (-3325 1875);
FORCEPROP 1 LAST HDL_TAP TRUE
J 0
(-3000 1700);
DISPLAY 0.872340 (-3000 1700);
DISPLAY INVISIBLE (-3000 1700);
FORCEPROP 1 LAST PATH I238
J 0
(-3327 1825);
DISPLAY 0.872340 (-3327 1825);
PAINT GREEN (-3327 1825);
DISPLAY INVISIBLE (-3327 1825);
FORCEADD TAP..1
(-3325 1775);
FORCEPROP 3 LASTPIN (-3375 1775) SIG_NAME M_H_CPU0_SB_CB<3>
J 0
(-3365 1785);
DISPLAY 0.659574 (-3365 1785);
PAINT MONO (-3365 1785);
DISPLAY INVISIBLE (-3365 1785);
FORCEPROP 1 LASTPIN (-3375 1775) BN 3
J 0
(-3387 1783);
DISPLAY 0.489362 (-3387 1783);
PAINT GREEN (-3387 1783);
FORCEPROP 2 LAST CDS_LIB mstr_standard
J 2
(-3325 1775);
DISPLAY 0.723404 (-3325 1775);
PAINT MONO (-3325 1775);
DISPLAY INVISIBLE (-3325 1775);
FORCEPROP 1 LAST BODY_TYPE PLUMBING
J 0
(-3325 1825);
DISPLAY 0.872340 (-3325 1825);
PAINT GREEN (-3325 1825);
DISPLAY INVISIBLE (-3325 1825);
FORCEPROP 1 LAST HDL_TAP TRUE
J 0
(-3000 1650);
DISPLAY 0.872340 (-3000 1650);
DISPLAY INVISIBLE (-3000 1650);
FORCEPROP 1 LAST PATH I239
J 0
(-3327 1775);
DISPLAY 0.872340 (-3327 1775);
PAINT GREEN (-3327 1775);
DISPLAY INVISIBLE (-3327 1775);
FORCEADD TAP..1
(-3325 1725);
FORCEPROP 3 LASTPIN (-3375 1725) SIG_NAME M_H_CPU0_SB_CB<4>
J 0
(-3365 1735);
DISPLAY 0.659574 (-3365 1735);
PAINT MONO (-3365 1735);
DISPLAY INVISIBLE (-3365 1735);
FORCEPROP 1 LASTPIN (-3375 1725) BN 4
J 0
(-3387 1733);
DISPLAY 0.489362 (-3387 1733);
PAINT GREEN (-3387 1733);
FORCEPROP 2 LAST CDS_LIB mstr_standard
J 2
(-3325 1725);
DISPLAY 0.723404 (-3325 1725);
PAINT MONO (-3325 1725);
DISPLAY INVISIBLE (-3325 1725);
FORCEPROP 1 LAST BODY_TYPE PLUMBING
J 0
(-3325 1775);
DISPLAY 0.872340 (-3325 1775);
PAINT GREEN (-3325 1775);
DISPLAY INVISIBLE (-3325 1775);
FORCEPROP 1 LAST HDL_TAP TRUE
J 0
(-3000 1600);
DISPLAY 0.872340 (-3000 1600);
DISPLAY INVISIBLE (-3000 1600);
FORCEPROP 1 LAST PATH I240
J 0
(-3327 1725);
DISPLAY 0.872340 (-3327 1725);
PAINT GREEN (-3327 1725);
DISPLAY INVISIBLE (-3327 1725);
FORCEADD TAP..1
(-3325 1675);
FORCEPROP 3 LASTPIN (-3375 1675) SIG_NAME M_H_CPU0_SB_CB<5>
J 0
(-3365 1685);
DISPLAY 0.659574 (-3365 1685);
PAINT MONO (-3365 1685);
DISPLAY INVISIBLE (-3365 1685);
FORCEPROP 1 LASTPIN (-3375 1675) BN 5
J 0
(-3387 1683);
DISPLAY 0.489362 (-3387 1683);
PAINT GREEN (-3387 1683);
FORCEPROP 2 LAST CDS_LIB mstr_standard
J 2
(-3325 1675);
DISPLAY 0.723404 (-3325 1675);
PAINT MONO (-3325 1675);
DISPLAY INVISIBLE (-3325 1675);
FORCEPROP 1 LAST BODY_TYPE PLUMBING
J 0
(-3325 1725);
DISPLAY 0.872340 (-3325 1725);
PAINT GREEN (-3325 1725);
DISPLAY INVISIBLE (-3325 1725);
FORCEPROP 1 LAST HDL_TAP TRUE
J 0
(-3000 1550);
DISPLAY 0.872340 (-3000 1550);
DISPLAY INVISIBLE (-3000 1550);
FORCEPROP 1 LAST PATH I241
J 0
(-3327 1675);
DISPLAY 0.872340 (-3327 1675);
PAINT GREEN (-3327 1675);
DISPLAY INVISIBLE (-3327 1675);
FORCEADD TAP..1
(-3325 1575);
FORCEPROP 3 LASTPIN (-3375 1575) SIG_NAME M_H_CPU0_SB_CB<7>
J 0
(-3365 1585);
DISPLAY 0.659574 (-3365 1585);
PAINT MONO (-3365 1585);
DISPLAY INVISIBLE (-3365 1585);
FORCEPROP 1 LASTPIN (-3375 1575) BN 7
J 0
(-3387 1583);
DISPLAY 0.489362 (-3387 1583);
PAINT GREEN (-3387 1583);
FORCEPROP 2 LAST CDS_LIB mstr_standard
J 2
(-3325 1575);
DISPLAY 0.723404 (-3325 1575);
PAINT MONO (-3325 1575);
DISPLAY INVISIBLE (-3325 1575);
FORCEPROP 1 LAST BODY_TYPE PLUMBING
J 0
(-3325 1625);
DISPLAY 0.872340 (-3325 1625);
PAINT GREEN (-3325 1625);
DISPLAY INVISIBLE (-3325 1625);
FORCEPROP 1 LAST HDL_TAP TRUE
J 0
(-3000 1450);
DISPLAY 0.872340 (-3000 1450);
DISPLAY INVISIBLE (-3000 1450);
FORCEPROP 1 LAST PATH I242
J 0
(-3327 1575);
DISPLAY 0.872340 (-3327 1575);
PAINT GREEN (-3327 1575);
DISPLAY INVISIBLE (-3327 1575);
FORCEADD TAP..1
(-3325 1625);
FORCEPROP 3 LASTPIN (-3375 1625) SIG_NAME M_H_CPU0_SB_CB<6>
J 0
(-3365 1635);
DISPLAY 0.659574 (-3365 1635);
PAINT MONO (-3365 1635);
DISPLAY INVISIBLE (-3365 1635);
FORCEPROP 1 LASTPIN (-3375 1625) BN 6
J 0
(-3387 1633);
DISPLAY 0.489362 (-3387 1633);
PAINT GREEN (-3387 1633);
FORCEPROP 2 LAST CDS_LIB mstr_standard
J 2
(-3325 1625);
DISPLAY 0.723404 (-3325 1625);
PAINT MONO (-3325 1625);
DISPLAY INVISIBLE (-3325 1625);
FORCEPROP 1 LAST BODY_TYPE PLUMBING
J 0
(-3325 1675);
DISPLAY 0.872340 (-3325 1675);
PAINT GREEN (-3325 1675);
DISPLAY INVISIBLE (-3325 1675);
FORCEPROP 1 LAST HDL_TAP TRUE
J 0
(-3000 1500);
DISPLAY 0.872340 (-3000 1500);
DISPLAY INVISIBLE (-3000 1500);
FORCEPROP 1 LAST PATH I243
J 0
(-3327 1625);
DISPLAY 0.872340 (-3327 1625);
PAINT GREEN (-3327 1625);
DISPLAY INVISIBLE (-3327 1625);
FORCEADD TAP..1
R 2
(-5750 5975);
FORCEPROP 3 LASTPIN (-5700 5975) SIG_NAME M_H_CPU0_SA_DQS_DP<0>
J 0
(-5690 5985);
DISPLAY 0.659574 (-5690 5985);
PAINT MONO (-5690 5985);
DISPLAY INVISIBLE (-5690 5985);
FORCEPROP 1 LASTPIN (-5700 5975) BN 0
J 2
(-5688 5983);
DISPLAY 0.489362 (-5688 5983);
PAINT GREEN (-5688 5983);
FORCEPROP 2 LAST CDS_LIB mstr_standard
J 2
(-5750 5975);
DISPLAY 0.723404 (-5750 5975);
PAINT MONO (-5750 5975);
DISPLAY INVISIBLE (-5750 5975);
FORCEPROP 1 LAST BODY_TYPE PLUMBING
J 2
(-5750 6025);
DISPLAY 0.872340 (-5750 6025);
PAINT GREEN (-5750 6025);
DISPLAY INVISIBLE (-5750 6025);
FORCEPROP 1 LAST HDL_TAP TRUE
J 2
(-6075 5850);
DISPLAY 0.872340 (-6075 5850);
DISPLAY INVISIBLE (-6075 5850);
FORCEPROP 1 LAST PATH I244
J 2
(-5748 5975);
DISPLAY 0.872340 (-5748 5975);
PAINT GREEN (-5748 5975);
DISPLAY INVISIBLE (-5748 5975);
FORCEADD TAP..1
R 2
(-5750 5775);
FORCEPROP 3 LASTPIN (-5700 5775) SIG_NAME M_H_CPU0_SA_DQS_DP<2>
J 0
(-5690 5785);
DISPLAY 0.659574 (-5690 5785);
PAINT MONO (-5690 5785);
DISPLAY INVISIBLE (-5690 5785);
FORCEPROP 1 LASTPIN (-5700 5775) BN 2
J 2
(-5688 5783);
DISPLAY 0.489362 (-5688 5783);
PAINT GREEN (-5688 5783);
FORCEPROP 2 LAST CDS_LIB mstr_standard
J 2
(-5750 5775);
DISPLAY 0.723404 (-5750 5775);
PAINT MONO (-5750 5775);
DISPLAY INVISIBLE (-5750 5775);
FORCEPROP 1 LAST BODY_TYPE PLUMBING
J 2
(-5750 5825);
DISPLAY 0.872340 (-5750 5825);
PAINT GREEN (-5750 5825);
DISPLAY INVISIBLE (-5750 5825);
FORCEPROP 1 LAST HDL_TAP TRUE
J 2
(-6075 5650);
DISPLAY 0.872340 (-6075 5650);
DISPLAY INVISIBLE (-6075 5650);
FORCEPROP 1 LAST PATH I245
J 2
(-5748 5775);
DISPLAY 0.872340 (-5748 5775);
PAINT GREEN (-5748 5775);
DISPLAY INVISIBLE (-5748 5775);
FORCEADD TAP..1
R 2
(-5750 5875);
FORCEPROP 3 LASTPIN (-5700 5875) SIG_NAME M_H_CPU0_SA_DQS_DP<1>
J 0
(-5690 5885);
DISPLAY 0.659574 (-5690 5885);
PAINT MONO (-5690 5885);
DISPLAY INVISIBLE (-5690 5885);
FORCEPROP 1 LASTPIN (-5700 5875) BN 1
J 2
(-5688 5883);
DISPLAY 0.489362 (-5688 5883);
PAINT GREEN (-5688 5883);
FORCEPROP 2 LAST CDS_LIB mstr_standard
J 2
(-5750 5875);
DISPLAY 0.723404 (-5750 5875);
PAINT MONO (-5750 5875);
DISPLAY INVISIBLE (-5750 5875);
FORCEPROP 1 LAST BODY_TYPE PLUMBING
J 2
(-5750 5925);
DISPLAY 0.872340 (-5750 5925);
PAINT GREEN (-5750 5925);
DISPLAY INVISIBLE (-5750 5925);
FORCEPROP 1 LAST HDL_TAP TRUE
J 2
(-6075 5750);
DISPLAY 0.872340 (-6075 5750);
DISPLAY INVISIBLE (-6075 5750);
FORCEPROP 1 LAST PATH I246
J 2
(-5748 5875);
DISPLAY 0.872340 (-5748 5875);
PAINT GREEN (-5748 5875);
DISPLAY INVISIBLE (-5748 5875);
FORCEADD TAP..1
R 2
(-5750 5675);
FORCEPROP 3 LASTPIN (-5700 5675) SIG_NAME M_H_CPU0_SA_DQS_DP<3>
J 0
(-5690 5685);
DISPLAY 0.659574 (-5690 5685);
PAINT MONO (-5690 5685);
DISPLAY INVISIBLE (-5690 5685);
FORCEPROP 1 LASTPIN (-5700 5675) BN 3
J 2
(-5688 5683);
DISPLAY 0.489362 (-5688 5683);
PAINT GREEN (-5688 5683);
FORCEPROP 2 LAST CDS_LIB mstr_standard
J 2
(-5750 5675);
DISPLAY 0.723404 (-5750 5675);
PAINT MONO (-5750 5675);
DISPLAY INVISIBLE (-5750 5675);
FORCEPROP 1 LAST BODY_TYPE PLUMBING
J 2
(-5750 5725);
DISPLAY 0.872340 (-5750 5725);
PAINT GREEN (-5750 5725);
DISPLAY INVISIBLE (-5750 5725);
FORCEPROP 1 LAST HDL_TAP TRUE
J 2
(-6075 5550);
DISPLAY 0.872340 (-6075 5550);
DISPLAY INVISIBLE (-6075 5550);
FORCEPROP 1 LAST PATH I247
J 2
(-5748 5675);
DISPLAY 0.872340 (-5748 5675);
PAINT GREEN (-5748 5675);
DISPLAY INVISIBLE (-5748 5675);
FORCEADD TAP..1
R 2
(-5950 5925);
FORCEPROP 3 LASTPIN (-5900 5925) SIG_NAME M_H_CPU0_SA_DQS_DN<0>
J 0
(-5890 5935);
DISPLAY 0.659574 (-5890 5935);
PAINT MONO (-5890 5935);
DISPLAY INVISIBLE (-5890 5935);
FORCEPROP 1 LASTPIN (-5900 5925) BN 0
J 2
(-5888 5933);
DISPLAY 0.489362 (-5888 5933);
PAINT GREEN (-5888 5933);
FORCEPROP 2 LAST CDS_LIB mstr_standard
J 2
(-5950 5925);
DISPLAY 0.723404 (-5950 5925);
PAINT MONO (-5950 5925);
DISPLAY INVISIBLE (-5950 5925);
FORCEPROP 1 LAST BODY_TYPE PLUMBING
J 2
(-5950 5975);
DISPLAY 0.872340 (-5950 5975);
PAINT GREEN (-5950 5975);
DISPLAY INVISIBLE (-5950 5975);
FORCEPROP 1 LAST HDL_TAP TRUE
J 2
(-6275 5800);
DISPLAY 0.872340 (-6275 5800);
DISPLAY INVISIBLE (-6275 5800);
FORCEPROP 1 LAST PATH I248
J 2
(-5948 5925);
DISPLAY 0.872340 (-5948 5925);
PAINT GREEN (-5948 5925);
DISPLAY INVISIBLE (-5948 5925);
FORCEADD TAP..1
R 2
(-5950 5825);
FORCEPROP 3 LASTPIN (-5900 5825) SIG_NAME M_H_CPU0_SA_DQS_DN<1>
J 0
(-5890 5835);
DISPLAY 0.659574 (-5890 5835);
PAINT MONO (-5890 5835);
DISPLAY INVISIBLE (-5890 5835);
FORCEPROP 1 LASTPIN (-5900 5825) BN 1
J 2
(-5888 5833);
DISPLAY 0.489362 (-5888 5833);
PAINT GREEN (-5888 5833);
FORCEPROP 2 LAST CDS_LIB mstr_standard
J 2
(-5950 5825);
DISPLAY 0.723404 (-5950 5825);
PAINT MONO (-5950 5825);
DISPLAY INVISIBLE (-5950 5825);
FORCEPROP 1 LAST BODY_TYPE PLUMBING
J 2
(-5950 5875);
DISPLAY 0.872340 (-5950 5875);
PAINT GREEN (-5950 5875);
DISPLAY INVISIBLE (-5950 5875);
FORCEPROP 1 LAST HDL_TAP TRUE
J 2
(-6275 5700);
DISPLAY 0.872340 (-6275 5700);
DISPLAY INVISIBLE (-6275 5700);
FORCEPROP 1 LAST PATH I249
J 2
(-5948 5825);
DISPLAY 0.872340 (-5948 5825);
PAINT GREEN (-5948 5825);
DISPLAY INVISIBLE (-5948 5825);
FORCEADD TAP..1
R 2
(-5950 5725);
FORCEPROP 3 LASTPIN (-5900 5725) SIG_NAME M_H_CPU0_SA_DQS_DN<2>
J 0
(-5890 5735);
DISPLAY 0.659574 (-5890 5735);
PAINT MONO (-5890 5735);
DISPLAY INVISIBLE (-5890 5735);
FORCEPROP 1 LASTPIN (-5900 5725) BN 2
J 2
(-5888 5733);
DISPLAY 0.489362 (-5888 5733);
PAINT GREEN (-5888 5733);
FORCEPROP 2 LAST CDS_LIB mstr_standard
J 2
(-5950 5725);
DISPLAY 0.723404 (-5950 5725);
PAINT MONO (-5950 5725);
DISPLAY INVISIBLE (-5950 5725);
FORCEPROP 1 LAST BODY_TYPE PLUMBING
J 2
(-5950 5775);
DISPLAY 0.872340 (-5950 5775);
PAINT GREEN (-5950 5775);
DISPLAY INVISIBLE (-5950 5775);
FORCEPROP 1 LAST HDL_TAP TRUE
J 2
(-6275 5600);
DISPLAY 0.872340 (-6275 5600);
DISPLAY INVISIBLE (-6275 5600);
FORCEPROP 1 LAST PATH I250
J 2
(-5948 5725);
DISPLAY 0.872340 (-5948 5725);
PAINT GREEN (-5948 5725);
DISPLAY INVISIBLE (-5948 5725);
FORCEADD TAP..1
R 2
(-5750 5575);
FORCEPROP 3 LASTPIN (-5700 5575) SIG_NAME M_H_CPU0_SA_DQS_DP<4>
J 0
(-5690 5585);
DISPLAY 0.659574 (-5690 5585);
PAINT MONO (-5690 5585);
DISPLAY INVISIBLE (-5690 5585);
FORCEPROP 1 LASTPIN (-5700 5575) BN 4
J 2
(-5688 5583);
DISPLAY 0.489362 (-5688 5583);
PAINT GREEN (-5688 5583);
FORCEPROP 2 LAST CDS_LIB mstr_standard
J 2
(-5750 5575);
DISPLAY 0.723404 (-5750 5575);
PAINT MONO (-5750 5575);
DISPLAY INVISIBLE (-5750 5575);
FORCEPROP 1 LAST BODY_TYPE PLUMBING
J 2
(-5750 5625);
DISPLAY 0.872340 (-5750 5625);
PAINT GREEN (-5750 5625);
DISPLAY INVISIBLE (-5750 5625);
FORCEPROP 1 LAST HDL_TAP TRUE
J 2
(-6075 5450);
DISPLAY 0.872340 (-6075 5450);
DISPLAY INVISIBLE (-6075 5450);
FORCEPROP 1 LAST PATH I251
J 2
(-5748 5575);
DISPLAY 0.872340 (-5748 5575);
PAINT GREEN (-5748 5575);
DISPLAY INVISIBLE (-5748 5575);
FORCEADD TAP..1
R 2
(-5750 5475);
FORCEPROP 3 LASTPIN (-5700 5475) SIG_NAME M_H_CPU0_SA_DQS_DP<5>
J 0
(-5690 5485);
DISPLAY 0.659574 (-5690 5485);
PAINT MONO (-5690 5485);
DISPLAY INVISIBLE (-5690 5485);
FORCEPROP 1 LASTPIN (-5700 5475) BN 5
J 2
(-5688 5483);
DISPLAY 0.489362 (-5688 5483);
PAINT GREEN (-5688 5483);
FORCEPROP 2 LAST CDS_LIB mstr_standard
J 2
(-5750 5475);
DISPLAY 0.723404 (-5750 5475);
PAINT MONO (-5750 5475);
DISPLAY INVISIBLE (-5750 5475);
FORCEPROP 1 LAST BODY_TYPE PLUMBING
J 2
(-5750 5525);
DISPLAY 0.872340 (-5750 5525);
PAINT GREEN (-5750 5525);
DISPLAY INVISIBLE (-5750 5525);
FORCEPROP 1 LAST HDL_TAP TRUE
J 2
(-6075 5350);
DISPLAY 0.872340 (-6075 5350);
DISPLAY INVISIBLE (-6075 5350);
FORCEPROP 1 LAST PATH I252
J 2
(-5748 5475);
DISPLAY 0.872340 (-5748 5475);
PAINT GREEN (-5748 5475);
DISPLAY INVISIBLE (-5748 5475);
FORCEADD TAP..1
R 2
(-5950 5625);
FORCEPROP 3 LASTPIN (-5900 5625) SIG_NAME M_H_CPU0_SA_DQS_DN<3>
J 0
(-5890 5635);
DISPLAY 0.659574 (-5890 5635);
PAINT MONO (-5890 5635);
DISPLAY INVISIBLE (-5890 5635);
FORCEPROP 1 LASTPIN (-5900 5625) BN 3
J 2
(-5888 5633);
DISPLAY 0.489362 (-5888 5633);
PAINT GREEN (-5888 5633);
FORCEPROP 2 LAST CDS_LIB mstr_standard
J 2
(-5950 5625);
DISPLAY 0.723404 (-5950 5625);
PAINT MONO (-5950 5625);
DISPLAY INVISIBLE (-5950 5625);
FORCEPROP 1 LAST BODY_TYPE PLUMBING
J 2
(-5950 5675);
DISPLAY 0.872340 (-5950 5675);
PAINT GREEN (-5950 5675);
DISPLAY INVISIBLE (-5950 5675);
FORCEPROP 1 LAST HDL_TAP TRUE
J 2
(-6275 5500);
DISPLAY 0.872340 (-6275 5500);
DISPLAY INVISIBLE (-6275 5500);
FORCEPROP 1 LAST PATH I253
J 2
(-5948 5625);
DISPLAY 0.872340 (-5948 5625);
PAINT GREEN (-5948 5625);
DISPLAY INVISIBLE (-5948 5625);
FORCEADD TAP..1
R 2
(-5750 5375);
FORCEPROP 3 LASTPIN (-5700 5375) SIG_NAME M_H_CPU0_SA_DQS_DP<6>
J 0
(-5690 5385);
DISPLAY 0.659574 (-5690 5385);
PAINT MONO (-5690 5385);
DISPLAY INVISIBLE (-5690 5385);
FORCEPROP 1 LASTPIN (-5700 5375) BN 6
J 2
(-5688 5383);
DISPLAY 0.489362 (-5688 5383);
PAINT GREEN (-5688 5383);
FORCEPROP 2 LAST CDS_LIB mstr_standard
J 2
(-5750 5375);
DISPLAY 0.723404 (-5750 5375);
PAINT MONO (-5750 5375);
DISPLAY INVISIBLE (-5750 5375);
FORCEPROP 1 LAST BODY_TYPE PLUMBING
J 2
(-5750 5425);
DISPLAY 0.872340 (-5750 5425);
PAINT GREEN (-5750 5425);
DISPLAY INVISIBLE (-5750 5425);
FORCEPROP 1 LAST HDL_TAP TRUE
J 2
(-6075 5250);
DISPLAY 0.872340 (-6075 5250);
DISPLAY INVISIBLE (-6075 5250);
FORCEPROP 1 LAST PATH I254
J 2
(-5748 5375);
DISPLAY 0.872340 (-5748 5375);
PAINT GREEN (-5748 5375);
DISPLAY INVISIBLE (-5748 5375);
FORCEADD TAP..1
R 2
(-5750 5275);
FORCEPROP 3 LASTPIN (-5700 5275) SIG_NAME M_H_CPU0_SA_DQS_DP<7>
J 0
(-5690 5285);
DISPLAY 0.659574 (-5690 5285);
PAINT MONO (-5690 5285);
DISPLAY INVISIBLE (-5690 5285);
FORCEPROP 1 LASTPIN (-5700 5275) BN 7
J 2
(-5688 5283);
DISPLAY 0.489362 (-5688 5283);
PAINT GREEN (-5688 5283);
FORCEPROP 2 LAST CDS_LIB mstr_standard
J 2
(-5750 5275);
DISPLAY 0.723404 (-5750 5275);
PAINT MONO (-5750 5275);
DISPLAY INVISIBLE (-5750 5275);
FORCEPROP 1 LAST BODY_TYPE PLUMBING
J 2
(-5750 5325);
DISPLAY 0.872340 (-5750 5325);
PAINT GREEN (-5750 5325);
DISPLAY INVISIBLE (-5750 5325);
FORCEPROP 1 LAST HDL_TAP TRUE
J 2
(-6075 5150);
DISPLAY 0.872340 (-6075 5150);
DISPLAY INVISIBLE (-6075 5150);
FORCEPROP 1 LAST PATH I255
J 2
(-5748 5275);
DISPLAY 0.872340 (-5748 5275);
PAINT GREEN (-5748 5275);
DISPLAY INVISIBLE (-5748 5275);
FORCEADD TAP..1
R 2
(-5750 5175);
FORCEPROP 3 LASTPIN (-5700 5175) SIG_NAME M_H_CPU0_SA_DQS_DP<8>
J 0
(-5690 5185);
DISPLAY 0.659574 (-5690 5185);
PAINT MONO (-5690 5185);
DISPLAY INVISIBLE (-5690 5185);
FORCEPROP 1 LASTPIN (-5700 5175) BN 8
J 2
(-5688 5183);
DISPLAY 0.489362 (-5688 5183);
PAINT GREEN (-5688 5183);
FORCEPROP 2 LAST CDS_LIB mstr_standard
J 2
(-5750 5175);
DISPLAY 0.723404 (-5750 5175);
PAINT MONO (-5750 5175);
DISPLAY INVISIBLE (-5750 5175);
FORCEPROP 1 LAST BODY_TYPE PLUMBING
J 2
(-5750 5225);
DISPLAY 0.872340 (-5750 5225);
PAINT GREEN (-5750 5225);
DISPLAY INVISIBLE (-5750 5225);
FORCEPROP 1 LAST HDL_TAP TRUE
J 2
(-6075 5050);
DISPLAY 0.872340 (-6075 5050);
DISPLAY INVISIBLE (-6075 5050);
FORCEPROP 1 LAST PATH I256
J 2
(-5748 5175);
DISPLAY 0.872340 (-5748 5175);
PAINT GREEN (-5748 5175);
DISPLAY INVISIBLE (-5748 5175);
FORCEADD TAP..1
R 2
(-5950 5525);
FORCEPROP 3 LASTPIN (-5900 5525) SIG_NAME M_H_CPU0_SA_DQS_DN<4>
J 0
(-5890 5535);
DISPLAY 0.659574 (-5890 5535);
PAINT MONO (-5890 5535);
DISPLAY INVISIBLE (-5890 5535);
FORCEPROP 1 LASTPIN (-5900 5525) BN 4
J 2
(-5888 5533);
DISPLAY 0.489362 (-5888 5533);
PAINT GREEN (-5888 5533);
FORCEPROP 2 LAST CDS_LIB mstr_standard
J 2
(-5950 5525);
DISPLAY 0.723404 (-5950 5525);
PAINT MONO (-5950 5525);
DISPLAY INVISIBLE (-5950 5525);
FORCEPROP 1 LAST BODY_TYPE PLUMBING
J 2
(-5950 5575);
DISPLAY 0.872340 (-5950 5575);
PAINT GREEN (-5950 5575);
DISPLAY INVISIBLE (-5950 5575);
FORCEPROP 1 LAST HDL_TAP TRUE
J 2
(-6275 5400);
DISPLAY 0.872340 (-6275 5400);
DISPLAY INVISIBLE (-6275 5400);
FORCEPROP 1 LAST PATH I257
J 2
(-5948 5525);
DISPLAY 0.872340 (-5948 5525);
PAINT GREEN (-5948 5525);
DISPLAY INVISIBLE (-5948 5525);
FORCEADD TAP..1
R 2
(-5950 5425);
FORCEPROP 3 LASTPIN (-5900 5425) SIG_NAME M_H_CPU0_SA_DQS_DN<5>
J 0
(-5890 5435);
DISPLAY 0.659574 (-5890 5435);
PAINT MONO (-5890 5435);
DISPLAY INVISIBLE (-5890 5435);
FORCEPROP 1 LASTPIN (-5900 5425) BN 5
J 2
(-5888 5433);
DISPLAY 0.489362 (-5888 5433);
PAINT GREEN (-5888 5433);
FORCEPROP 2 LAST CDS_LIB mstr_standard
J 2
(-5950 5425);
DISPLAY 0.723404 (-5950 5425);
PAINT MONO (-5950 5425);
DISPLAY INVISIBLE (-5950 5425);
FORCEPROP 1 LAST BODY_TYPE PLUMBING
J 2
(-5950 5475);
DISPLAY 0.872340 (-5950 5475);
PAINT GREEN (-5950 5475);
DISPLAY INVISIBLE (-5950 5475);
FORCEPROP 1 LAST HDL_TAP TRUE
J 2
(-6275 5300);
DISPLAY 0.872340 (-6275 5300);
DISPLAY INVISIBLE (-6275 5300);
FORCEPROP 1 LAST PATH I258
J 2
(-5948 5425);
DISPLAY 0.872340 (-5948 5425);
PAINT GREEN (-5948 5425);
DISPLAY INVISIBLE (-5948 5425);
FORCEADD TAP..1
R 2
(-5950 5325);
FORCEPROP 3 LASTPIN (-5900 5325) SIG_NAME M_H_CPU0_SA_DQS_DN<6>
J 0
(-5890 5335);
DISPLAY 0.659574 (-5890 5335);
PAINT MONO (-5890 5335);
DISPLAY INVISIBLE (-5890 5335);
FORCEPROP 1 LASTPIN (-5900 5325) BN 6
J 2
(-5888 5333);
DISPLAY 0.489362 (-5888 5333);
PAINT GREEN (-5888 5333);
FORCEPROP 2 LAST CDS_LIB mstr_standard
J 2
(-5950 5325);
DISPLAY 0.723404 (-5950 5325);
PAINT MONO (-5950 5325);
DISPLAY INVISIBLE (-5950 5325);
FORCEPROP 1 LAST BODY_TYPE PLUMBING
J 2
(-5950 5375);
DISPLAY 0.872340 (-5950 5375);
PAINT GREEN (-5950 5375);
DISPLAY INVISIBLE (-5950 5375);
FORCEPROP 1 LAST HDL_TAP TRUE
J 2
(-6275 5200);
DISPLAY 0.872340 (-6275 5200);
DISPLAY INVISIBLE (-6275 5200);
FORCEPROP 1 LAST PATH I259
J 2
(-5948 5325);
DISPLAY 0.872340 (-5948 5325);
PAINT GREEN (-5948 5325);
DISPLAY INVISIBLE (-5948 5325);
FORCEADD TAP..1
R 2
(-5950 5125);
FORCEPROP 3 LASTPIN (-5900 5125) SIG_NAME M_H_CPU0_SA_DQS_DN<8>
J 0
(-5890 5135);
DISPLAY 0.659574 (-5890 5135);
PAINT MONO (-5890 5135);
DISPLAY INVISIBLE (-5890 5135);
FORCEPROP 1 LASTPIN (-5900 5125) BN 8
J 2
(-5888 5133);
DISPLAY 0.489362 (-5888 5133);
PAINT GREEN (-5888 5133);
FORCEPROP 2 LAST CDS_LIB mstr_standard
J 2
(-5950 5125);
DISPLAY 0.723404 (-5950 5125);
PAINT MONO (-5950 5125);
DISPLAY INVISIBLE (-5950 5125);
FORCEPROP 1 LAST BODY_TYPE PLUMBING
J 2
(-5950 5175);
DISPLAY 0.872340 (-5950 5175);
PAINT GREEN (-5950 5175);
DISPLAY INVISIBLE (-5950 5175);
FORCEPROP 1 LAST HDL_TAP TRUE
J 2
(-6275 5000);
DISPLAY 0.872340 (-6275 5000);
DISPLAY INVISIBLE (-6275 5000);
FORCEPROP 1 LAST PATH I260
J 2
(-5948 5125);
DISPLAY 0.872340 (-5948 5125);
PAINT GREEN (-5948 5125);
DISPLAY INVISIBLE (-5948 5125);
FORCEADD TAP..1
R 2
(-5950 5225);
FORCEPROP 3 LASTPIN (-5900 5225) SIG_NAME M_H_CPU0_SA_DQS_DN<7>
J 0
(-5890 5235);
DISPLAY 0.659574 (-5890 5235);
PAINT MONO (-5890 5235);
DISPLAY INVISIBLE (-5890 5235);
FORCEPROP 1 LASTPIN (-5900 5225) BN 7
J 2
(-5888 5233);
DISPLAY 0.489362 (-5888 5233);
PAINT GREEN (-5888 5233);
FORCEPROP 2 LAST CDS_LIB mstr_standard
J 2
(-5950 5225);
DISPLAY 0.723404 (-5950 5225);
PAINT MONO (-5950 5225);
DISPLAY INVISIBLE (-5950 5225);
FORCEPROP 1 LAST BODY_TYPE PLUMBING
J 2
(-5950 5275);
DISPLAY 0.872340 (-5950 5275);
PAINT GREEN (-5950 5275);
DISPLAY INVISIBLE (-5950 5275);
FORCEPROP 1 LAST HDL_TAP TRUE
J 2
(-6275 5100);
DISPLAY 0.872340 (-6275 5100);
DISPLAY INVISIBLE (-6275 5100);
FORCEPROP 1 LAST PATH I261
J 2
(-5948 5225);
DISPLAY 0.872340 (-5948 5225);
PAINT GREEN (-5948 5225);
DISPLAY INVISIBLE (-5948 5225);
FORCEADD TAP..1
R 2
(-5750 5075);
FORCEPROP 3 LASTPIN (-5700 5075) SIG_NAME M_H_CPU0_SA_DQS_DP<9>
J 0
(-5690 5085);
DISPLAY 0.659574 (-5690 5085);
PAINT MONO (-5690 5085);
DISPLAY INVISIBLE (-5690 5085);
FORCEPROP 1 LASTPIN (-5700 5075) BN 9
J 2
(-5688 5083);
DISPLAY 0.489362 (-5688 5083);
PAINT GREEN (-5688 5083);
FORCEPROP 2 LAST CDS_LIB mstr_standard
J 2
(-5750 5075);
DISPLAY 0.723404 (-5750 5075);
PAINT MONO (-5750 5075);
DISPLAY INVISIBLE (-5750 5075);
FORCEPROP 1 LAST BODY_TYPE PLUMBING
J 2
(-5750 5125);
DISPLAY 0.872340 (-5750 5125);
PAINT GREEN (-5750 5125);
DISPLAY INVISIBLE (-5750 5125);
FORCEPROP 1 LAST HDL_TAP TRUE
J 2
(-6075 4950);
DISPLAY 0.872340 (-6075 4950);
DISPLAY INVISIBLE (-6075 4950);
FORCEPROP 1 LAST PATH I262
J 2
(-5748 5075);
DISPLAY 0.872340 (-5748 5075);
PAINT GREEN (-5748 5075);
DISPLAY INVISIBLE (-5748 5075);
FORCEADD TAP..1
R 2
(-5750 4925);
FORCEPROP 3 LASTPIN (-5700 4925) SIG_NAME M_H_CPU0_SB_DQS_DP<0>
J 0
(-5690 4935);
DISPLAY 0.659574 (-5690 4935);
PAINT MONO (-5690 4935);
DISPLAY INVISIBLE (-5690 4935);
FORCEPROP 1 LASTPIN (-5700 4925) BN 0
J 2
(-5688 4933);
DISPLAY 0.489362 (-5688 4933);
PAINT GREEN (-5688 4933);
FORCEPROP 2 LAST CDS_LIB mstr_standard
J 2
(-5750 4925);
DISPLAY 0.723404 (-5750 4925);
PAINT MONO (-5750 4925);
DISPLAY INVISIBLE (-5750 4925);
FORCEPROP 1 LAST BODY_TYPE PLUMBING
J 2
(-5750 4975);
DISPLAY 0.872340 (-5750 4975);
PAINT GREEN (-5750 4975);
DISPLAY INVISIBLE (-5750 4975);
FORCEPROP 1 LAST HDL_TAP TRUE
J 2
(-6075 4800);
DISPLAY 0.872340 (-6075 4800);
DISPLAY INVISIBLE (-6075 4800);
FORCEPROP 1 LAST PATH I263
J 2
(-5748 4925);
DISPLAY 0.872340 (-5748 4925);
PAINT GREEN (-5748 4925);
DISPLAY INVISIBLE (-5748 4925);
FORCEADD TAP..1
R 2
(-5750 4825);
FORCEPROP 3 LASTPIN (-5700 4825) SIG_NAME M_H_CPU0_SB_DQS_DP<1>
J 0
(-5690 4835);
DISPLAY 0.659574 (-5690 4835);
PAINT MONO (-5690 4835);
DISPLAY INVISIBLE (-5690 4835);
FORCEPROP 1 LASTPIN (-5700 4825) BN 1
J 2
(-5688 4833);
DISPLAY 0.489362 (-5688 4833);
PAINT GREEN (-5688 4833);
FORCEPROP 2 LAST CDS_LIB mstr_standard
J 2
(-5750 4825);
DISPLAY 0.723404 (-5750 4825);
PAINT MONO (-5750 4825);
DISPLAY INVISIBLE (-5750 4825);
FORCEPROP 1 LAST BODY_TYPE PLUMBING
J 2
(-5750 4875);
DISPLAY 0.872340 (-5750 4875);
PAINT GREEN (-5750 4875);
DISPLAY INVISIBLE (-5750 4875);
FORCEPROP 1 LAST HDL_TAP TRUE
J 2
(-6075 4700);
DISPLAY 0.872340 (-6075 4700);
DISPLAY INVISIBLE (-6075 4700);
FORCEPROP 1 LAST PATH I264
J 2
(-5748 4825);
DISPLAY 0.872340 (-5748 4825);
PAINT GREEN (-5748 4825);
DISPLAY INVISIBLE (-5748 4825);
FORCEADD TAP..1
R 2
(-5750 4725);
FORCEPROP 3 LASTPIN (-5700 4725) SIG_NAME M_H_CPU0_SB_DQS_DP<2>
J 0
(-5690 4735);
DISPLAY 0.659574 (-5690 4735);
PAINT MONO (-5690 4735);
DISPLAY INVISIBLE (-5690 4735);
FORCEPROP 1 LASTPIN (-5700 4725) BN 2
J 2
(-5688 4733);
DISPLAY 0.489362 (-5688 4733);
PAINT GREEN (-5688 4733);
FORCEPROP 2 LAST CDS_LIB mstr_standard
J 2
(-5750 4725);
DISPLAY 0.723404 (-5750 4725);
PAINT MONO (-5750 4725);
DISPLAY INVISIBLE (-5750 4725);
FORCEPROP 1 LAST BODY_TYPE PLUMBING
J 2
(-5750 4775);
DISPLAY 0.872340 (-5750 4775);
PAINT GREEN (-5750 4775);
DISPLAY INVISIBLE (-5750 4775);
FORCEPROP 1 LAST HDL_TAP TRUE
J 2
(-6075 4600);
DISPLAY 0.872340 (-6075 4600);
DISPLAY INVISIBLE (-6075 4600);
FORCEPROP 1 LAST PATH I265
J 2
(-5748 4725);
DISPLAY 0.872340 (-5748 4725);
PAINT GREEN (-5748 4725);
DISPLAY INVISIBLE (-5748 4725);
FORCEADD TAP..1
R 2
(-5750 4625);
FORCEPROP 3 LASTPIN (-5700 4625) SIG_NAME M_H_CPU0_SB_DQS_DP<3>
J 0
(-5690 4635);
DISPLAY 0.659574 (-5690 4635);
PAINT MONO (-5690 4635);
DISPLAY INVISIBLE (-5690 4635);
FORCEPROP 1 LASTPIN (-5700 4625) BN 3
J 2
(-5688 4633);
DISPLAY 0.489362 (-5688 4633);
PAINT GREEN (-5688 4633);
FORCEPROP 2 LAST CDS_LIB mstr_standard
J 2
(-5750 4625);
DISPLAY 0.723404 (-5750 4625);
PAINT MONO (-5750 4625);
DISPLAY INVISIBLE (-5750 4625);
FORCEPROP 1 LAST BODY_TYPE PLUMBING
J 2
(-5750 4675);
DISPLAY 0.872340 (-5750 4675);
PAINT GREEN (-5750 4675);
DISPLAY INVISIBLE (-5750 4675);
FORCEPROP 1 LAST HDL_TAP TRUE
J 2
(-6075 4500);
DISPLAY 0.872340 (-6075 4500);
DISPLAY INVISIBLE (-6075 4500);
FORCEPROP 1 LAST PATH I266
J 2
(-5748 4625);
DISPLAY 0.872340 (-5748 4625);
PAINT GREEN (-5748 4625);
DISPLAY INVISIBLE (-5748 4625);
FORCEADD TAP..1
R 2
(-5950 5025);
FORCEPROP 3 LASTPIN (-5900 5025) SIG_NAME M_H_CPU0_SA_DQS_DN<9>
J 0
(-5890 5035);
DISPLAY 0.659574 (-5890 5035);
PAINT MONO (-5890 5035);
DISPLAY INVISIBLE (-5890 5035);
FORCEPROP 1 LASTPIN (-5900 5025) BN 9
J 2
(-5888 5033);
DISPLAY 0.489362 (-5888 5033);
PAINT GREEN (-5888 5033);
FORCEPROP 2 LAST CDS_LIB mstr_standard
J 2
(-5950 5025);
DISPLAY 0.723404 (-5950 5025);
PAINT MONO (-5950 5025);
DISPLAY INVISIBLE (-5950 5025);
FORCEPROP 1 LAST BODY_TYPE PLUMBING
J 2
(-5950 5075);
DISPLAY 0.872340 (-5950 5075);
PAINT GREEN (-5950 5075);
DISPLAY INVISIBLE (-5950 5075);
FORCEPROP 1 LAST HDL_TAP TRUE
J 2
(-6275 4900);
DISPLAY 0.872340 (-6275 4900);
DISPLAY INVISIBLE (-6275 4900);
FORCEPROP 1 LAST PATH I267
J 2
(-5948 5025);
DISPLAY 0.872340 (-5948 5025);
PAINT GREEN (-5948 5025);
DISPLAY INVISIBLE (-5948 5025);
FORCEADD TAP..1
R 2
(-5950 4875);
FORCEPROP 3 LASTPIN (-5900 4875) SIG_NAME M_H_CPU0_SB_DQS_DN<0>
J 0
(-5890 4885);
DISPLAY 0.659574 (-5890 4885);
PAINT MONO (-5890 4885);
DISPLAY INVISIBLE (-5890 4885);
FORCEPROP 1 LASTPIN (-5900 4875) BN 0
J 2
(-5888 4883);
DISPLAY 0.489362 (-5888 4883);
PAINT GREEN (-5888 4883);
FORCEPROP 2 LAST CDS_LIB mstr_standard
J 2
(-5950 4875);
DISPLAY 0.723404 (-5950 4875);
PAINT MONO (-5950 4875);
DISPLAY INVISIBLE (-5950 4875);
FORCEPROP 1 LAST BODY_TYPE PLUMBING
J 2
(-5950 4925);
DISPLAY 0.872340 (-5950 4925);
PAINT GREEN (-5950 4925);
DISPLAY INVISIBLE (-5950 4925);
FORCEPROP 1 LAST HDL_TAP TRUE
J 2
(-6275 4750);
DISPLAY 0.872340 (-6275 4750);
DISPLAY INVISIBLE (-6275 4750);
FORCEPROP 1 LAST PATH I268
J 2
(-5948 4875);
DISPLAY 0.872340 (-5948 4875);
PAINT GREEN (-5948 4875);
DISPLAY INVISIBLE (-5948 4875);
FORCEADD TAP..1
R 2
(-5950 4775);
FORCEPROP 3 LASTPIN (-5900 4775) SIG_NAME M_H_CPU0_SB_DQS_DN<1>
J 0
(-5890 4785);
DISPLAY 0.659574 (-5890 4785);
PAINT MONO (-5890 4785);
DISPLAY INVISIBLE (-5890 4785);
FORCEPROP 1 LASTPIN (-5900 4775) BN 1
J 2
(-5888 4783);
DISPLAY 0.489362 (-5888 4783);
PAINT GREEN (-5888 4783);
FORCEPROP 2 LAST CDS_LIB mstr_standard
J 2
(-5950 4775);
DISPLAY 0.723404 (-5950 4775);
PAINT MONO (-5950 4775);
DISPLAY INVISIBLE (-5950 4775);
FORCEPROP 1 LAST BODY_TYPE PLUMBING
J 2
(-5950 4825);
DISPLAY 0.872340 (-5950 4825);
PAINT GREEN (-5950 4825);
DISPLAY INVISIBLE (-5950 4825);
FORCEPROP 1 LAST HDL_TAP TRUE
J 2
(-6275 4650);
DISPLAY 0.872340 (-6275 4650);
DISPLAY INVISIBLE (-6275 4650);
FORCEPROP 1 LAST PATH I269
J 2
(-5948 4775);
DISPLAY 0.872340 (-5948 4775);
PAINT GREEN (-5948 4775);
DISPLAY INVISIBLE (-5948 4775);
FORCEADD TAP..1
R 2
(-5950 4675);
FORCEPROP 3 LASTPIN (-5900 4675) SIG_NAME M_H_CPU0_SB_DQS_DN<2>
J 0
(-5890 4685);
DISPLAY 0.659574 (-5890 4685);
PAINT MONO (-5890 4685);
DISPLAY INVISIBLE (-5890 4685);
FORCEPROP 1 LASTPIN (-5900 4675) BN 2
J 2
(-5888 4683);
DISPLAY 0.489362 (-5888 4683);
PAINT GREEN (-5888 4683);
FORCEPROP 2 LAST CDS_LIB mstr_standard
J 2
(-5950 4675);
DISPLAY 0.723404 (-5950 4675);
PAINT MONO (-5950 4675);
DISPLAY INVISIBLE (-5950 4675);
FORCEPROP 1 LAST BODY_TYPE PLUMBING
J 2
(-5950 4725);
DISPLAY 0.872340 (-5950 4725);
PAINT GREEN (-5950 4725);
DISPLAY INVISIBLE (-5950 4725);
FORCEPROP 1 LAST HDL_TAP TRUE
J 2
(-6275 4550);
DISPLAY 0.872340 (-6275 4550);
DISPLAY INVISIBLE (-6275 4550);
FORCEPROP 1 LAST PATH I270
J 2
(-5948 4675);
DISPLAY 0.872340 (-5948 4675);
PAINT GREEN (-5948 4675);
DISPLAY INVISIBLE (-5948 4675);
FORCEADD TAP..1
R 2
(-5750 4525);
FORCEPROP 3 LASTPIN (-5700 4525) SIG_NAME M_H_CPU0_SB_DQS_DP<4>
J 0
(-5690 4535);
DISPLAY 0.659574 (-5690 4535);
PAINT MONO (-5690 4535);
DISPLAY INVISIBLE (-5690 4535);
FORCEPROP 1 LASTPIN (-5700 4525) BN 4
J 2
(-5688 4533);
DISPLAY 0.489362 (-5688 4533);
PAINT GREEN (-5688 4533);
FORCEPROP 2 LAST CDS_LIB mstr_standard
J 2
(-5750 4525);
DISPLAY 0.723404 (-5750 4525);
PAINT MONO (-5750 4525);
DISPLAY INVISIBLE (-5750 4525);
FORCEPROP 1 LAST BODY_TYPE PLUMBING
J 2
(-5750 4575);
DISPLAY 0.872340 (-5750 4575);
PAINT GREEN (-5750 4575);
DISPLAY INVISIBLE (-5750 4575);
FORCEPROP 1 LAST HDL_TAP TRUE
J 2
(-6075 4400);
DISPLAY 0.872340 (-6075 4400);
DISPLAY INVISIBLE (-6075 4400);
FORCEPROP 1 LAST PATH I271
J 2
(-5748 4525);
DISPLAY 0.872340 (-5748 4525);
PAINT GREEN (-5748 4525);
DISPLAY INVISIBLE (-5748 4525);
FORCEADD TAP..1
R 2
(-5750 4425);
FORCEPROP 3 LASTPIN (-5700 4425) SIG_NAME M_H_CPU0_SB_DQS_DP<5>
J 0
(-5690 4435);
DISPLAY 0.659574 (-5690 4435);
PAINT MONO (-5690 4435);
DISPLAY INVISIBLE (-5690 4435);
FORCEPROP 1 LASTPIN (-5700 4425) BN 5
J 2
(-5688 4433);
DISPLAY 0.489362 (-5688 4433);
PAINT GREEN (-5688 4433);
FORCEPROP 2 LAST CDS_LIB mstr_standard
J 2
(-5750 4425);
DISPLAY 0.723404 (-5750 4425);
PAINT MONO (-5750 4425);
DISPLAY INVISIBLE (-5750 4425);
FORCEPROP 1 LAST BODY_TYPE PLUMBING
J 2
(-5750 4475);
DISPLAY 0.872340 (-5750 4475);
PAINT GREEN (-5750 4475);
DISPLAY INVISIBLE (-5750 4475);
FORCEPROP 1 LAST HDL_TAP TRUE
J 2
(-6075 4300);
DISPLAY 0.872340 (-6075 4300);
DISPLAY INVISIBLE (-6075 4300);
FORCEPROP 1 LAST PATH I272
J 2
(-5748 4425);
DISPLAY 0.872340 (-5748 4425);
PAINT GREEN (-5748 4425);
DISPLAY INVISIBLE (-5748 4425);
FORCEADD TAP..1
R 2
(-5750 4325);
FORCEPROP 3 LASTPIN (-5700 4325) SIG_NAME M_H_CPU0_SB_DQS_DP<6>
J 0
(-5690 4335);
DISPLAY 0.659574 (-5690 4335);
PAINT MONO (-5690 4335);
DISPLAY INVISIBLE (-5690 4335);
FORCEPROP 1 LASTPIN (-5700 4325) BN 6
J 2
(-5688 4333);
DISPLAY 0.489362 (-5688 4333);
PAINT GREEN (-5688 4333);
FORCEPROP 2 LAST CDS_LIB mstr_standard
J 2
(-5750 4325);
DISPLAY 0.723404 (-5750 4325);
PAINT MONO (-5750 4325);
DISPLAY INVISIBLE (-5750 4325);
FORCEPROP 1 LAST BODY_TYPE PLUMBING
J 2
(-5750 4375);
DISPLAY 0.872340 (-5750 4375);
PAINT GREEN (-5750 4375);
DISPLAY INVISIBLE (-5750 4375);
FORCEPROP 1 LAST HDL_TAP TRUE
J 2
(-6075 4200);
DISPLAY 0.872340 (-6075 4200);
DISPLAY INVISIBLE (-6075 4200);
FORCEPROP 1 LAST PATH I273
J 2
(-5748 4325);
DISPLAY 0.872340 (-5748 4325);
PAINT GREEN (-5748 4325);
DISPLAY INVISIBLE (-5748 4325);
FORCEADD TAP..1
R 2
(-5750 4225);
FORCEPROP 3 LASTPIN (-5700 4225) SIG_NAME M_H_CPU0_SB_DQS_DP<7>
J 0
(-5690 4235);
DISPLAY 0.659574 (-5690 4235);
PAINT MONO (-5690 4235);
DISPLAY INVISIBLE (-5690 4235);
FORCEPROP 1 LASTPIN (-5700 4225) BN 7
J 2
(-5688 4233);
DISPLAY 0.489362 (-5688 4233);
PAINT GREEN (-5688 4233);
FORCEPROP 2 LAST CDS_LIB mstr_standard
J 2
(-5750 4225);
DISPLAY 0.723404 (-5750 4225);
PAINT MONO (-5750 4225);
DISPLAY INVISIBLE (-5750 4225);
FORCEPROP 1 LAST BODY_TYPE PLUMBING
J 2
(-5750 4275);
DISPLAY 0.872340 (-5750 4275);
PAINT GREEN (-5750 4275);
DISPLAY INVISIBLE (-5750 4275);
FORCEPROP 1 LAST HDL_TAP TRUE
J 2
(-6075 4100);
DISPLAY 0.872340 (-6075 4100);
DISPLAY INVISIBLE (-6075 4100);
FORCEPROP 1 LAST PATH I274
J 2
(-5748 4225);
DISPLAY 0.872340 (-5748 4225);
PAINT GREEN (-5748 4225);
DISPLAY INVISIBLE (-5748 4225);
FORCEADD TAP..1
R 2
(-5750 4125);
FORCEPROP 3 LASTPIN (-5700 4125) SIG_NAME M_H_CPU0_SB_DQS_DP<8>
J 0
(-5690 4135);
DISPLAY 0.659574 (-5690 4135);
PAINT MONO (-5690 4135);
DISPLAY INVISIBLE (-5690 4135);
FORCEPROP 1 LASTPIN (-5700 4125) BN 8
J 2
(-5688 4133);
DISPLAY 0.489362 (-5688 4133);
PAINT GREEN (-5688 4133);
FORCEPROP 2 LAST CDS_LIB mstr_standard
J 2
(-5750 4125);
DISPLAY 0.723404 (-5750 4125);
PAINT MONO (-5750 4125);
DISPLAY INVISIBLE (-5750 4125);
FORCEPROP 1 LAST BODY_TYPE PLUMBING
J 2
(-5750 4175);
DISPLAY 0.872340 (-5750 4175);
PAINT GREEN (-5750 4175);
DISPLAY INVISIBLE (-5750 4175);
FORCEPROP 1 LAST HDL_TAP TRUE
J 2
(-6075 4000);
DISPLAY 0.872340 (-6075 4000);
DISPLAY INVISIBLE (-6075 4000);
FORCEPROP 1 LAST PATH I275
J 2
(-5748 4125);
DISPLAY 0.872340 (-5748 4125);
PAINT GREEN (-5748 4125);
DISPLAY INVISIBLE (-5748 4125);
FORCEADD TAP..1
R 2
(-5950 4575);
FORCEPROP 3 LASTPIN (-5900 4575) SIG_NAME M_H_CPU0_SB_DQS_DN<3>
J 0
(-5890 4585);
DISPLAY 0.659574 (-5890 4585);
PAINT MONO (-5890 4585);
DISPLAY INVISIBLE (-5890 4585);
FORCEPROP 1 LASTPIN (-5900 4575) BN 3
J 2
(-5888 4583);
DISPLAY 0.489362 (-5888 4583);
PAINT GREEN (-5888 4583);
FORCEPROP 2 LAST CDS_LIB mstr_standard
J 2
(-5950 4575);
DISPLAY 0.723404 (-5950 4575);
PAINT MONO (-5950 4575);
DISPLAY INVISIBLE (-5950 4575);
FORCEPROP 1 LAST BODY_TYPE PLUMBING
J 2
(-5950 4625);
DISPLAY 0.872340 (-5950 4625);
PAINT GREEN (-5950 4625);
DISPLAY INVISIBLE (-5950 4625);
FORCEPROP 1 LAST HDL_TAP TRUE
J 2
(-6275 4450);
DISPLAY 0.872340 (-6275 4450);
DISPLAY INVISIBLE (-6275 4450);
FORCEPROP 1 LAST PATH I276
J 2
(-5948 4575);
DISPLAY 0.872340 (-5948 4575);
PAINT GREEN (-5948 4575);
DISPLAY INVISIBLE (-5948 4575);
FORCEADD TAP..1
R 2
(-5950 4475);
FORCEPROP 3 LASTPIN (-5900 4475) SIG_NAME M_H_CPU0_SB_DQS_DN<4>
J 0
(-5890 4485);
DISPLAY 0.659574 (-5890 4485);
PAINT MONO (-5890 4485);
DISPLAY INVISIBLE (-5890 4485);
FORCEPROP 1 LASTPIN (-5900 4475) BN 4
J 2
(-5888 4483);
DISPLAY 0.489362 (-5888 4483);
PAINT GREEN (-5888 4483);
FORCEPROP 2 LAST CDS_LIB mstr_standard
J 2
(-5950 4475);
DISPLAY 0.723404 (-5950 4475);
PAINT MONO (-5950 4475);
DISPLAY INVISIBLE (-5950 4475);
FORCEPROP 1 LAST BODY_TYPE PLUMBING
J 2
(-5950 4525);
DISPLAY 0.872340 (-5950 4525);
PAINT GREEN (-5950 4525);
DISPLAY INVISIBLE (-5950 4525);
FORCEPROP 1 LAST HDL_TAP TRUE
J 2
(-6275 4350);
DISPLAY 0.872340 (-6275 4350);
DISPLAY INVISIBLE (-6275 4350);
FORCEPROP 1 LAST PATH I277
J 2
(-5948 4475);
DISPLAY 0.872340 (-5948 4475);
PAINT GREEN (-5948 4475);
DISPLAY INVISIBLE (-5948 4475);
FORCEADD TAP..1
R 2
(-5950 4375);
FORCEPROP 3 LASTPIN (-5900 4375) SIG_NAME M_H_CPU0_SB_DQS_DN<5>
J 0
(-5890 4385);
DISPLAY 0.659574 (-5890 4385);
PAINT MONO (-5890 4385);
DISPLAY INVISIBLE (-5890 4385);
FORCEPROP 1 LASTPIN (-5900 4375) BN 5
J 2
(-5888 4383);
DISPLAY 0.489362 (-5888 4383);
PAINT GREEN (-5888 4383);
FORCEPROP 2 LAST CDS_LIB mstr_standard
J 2
(-5950 4375);
DISPLAY 0.723404 (-5950 4375);
PAINT MONO (-5950 4375);
DISPLAY INVISIBLE (-5950 4375);
FORCEPROP 1 LAST BODY_TYPE PLUMBING
J 2
(-5950 4425);
DISPLAY 0.872340 (-5950 4425);
PAINT GREEN (-5950 4425);
DISPLAY INVISIBLE (-5950 4425);
FORCEPROP 1 LAST HDL_TAP TRUE
J 2
(-6275 4250);
DISPLAY 0.872340 (-6275 4250);
DISPLAY INVISIBLE (-6275 4250);
FORCEPROP 1 LAST PATH I278
J 2
(-5948 4375);
DISPLAY 0.872340 (-5948 4375);
PAINT GREEN (-5948 4375);
DISPLAY INVISIBLE (-5948 4375);
FORCEADD TAP..1
R 2
(-5950 4275);
FORCEPROP 3 LASTPIN (-5900 4275) SIG_NAME M_H_CPU0_SB_DQS_DN<6>
J 0
(-5890 4285);
DISPLAY 0.659574 (-5890 4285);
PAINT MONO (-5890 4285);
DISPLAY INVISIBLE (-5890 4285);
FORCEPROP 1 LASTPIN (-5900 4275) BN 6
J 2
(-5888 4283);
DISPLAY 0.489362 (-5888 4283);
PAINT GREEN (-5888 4283);
FORCEPROP 2 LAST CDS_LIB mstr_standard
J 2
(-5950 4275);
DISPLAY 0.723404 (-5950 4275);
PAINT MONO (-5950 4275);
DISPLAY INVISIBLE (-5950 4275);
FORCEPROP 1 LAST BODY_TYPE PLUMBING
J 2
(-5950 4325);
DISPLAY 0.872340 (-5950 4325);
PAINT GREEN (-5950 4325);
DISPLAY INVISIBLE (-5950 4325);
FORCEPROP 1 LAST HDL_TAP TRUE
J 2
(-6275 4150);
DISPLAY 0.872340 (-6275 4150);
DISPLAY INVISIBLE (-6275 4150);
FORCEPROP 1 LAST PATH I279
J 2
(-5948 4275);
DISPLAY 0.872340 (-5948 4275);
PAINT GREEN (-5948 4275);
DISPLAY INVISIBLE (-5948 4275);
FORCEADD TAP..1
R 2
(-5950 4175);
FORCEPROP 3 LASTPIN (-5900 4175) SIG_NAME M_H_CPU0_SB_DQS_DN<7>
J 0
(-5890 4185);
DISPLAY 0.659574 (-5890 4185);
PAINT MONO (-5890 4185);
DISPLAY INVISIBLE (-5890 4185);
FORCEPROP 1 LASTPIN (-5900 4175) BN 7
J 2
(-5888 4183);
DISPLAY 0.489362 (-5888 4183);
PAINT GREEN (-5888 4183);
FORCEPROP 2 LAST CDS_LIB mstr_standard
J 2
(-5950 4175);
DISPLAY 0.723404 (-5950 4175);
PAINT MONO (-5950 4175);
DISPLAY INVISIBLE (-5950 4175);
FORCEPROP 1 LAST BODY_TYPE PLUMBING
J 2
(-5950 4225);
DISPLAY 0.872340 (-5950 4225);
PAINT GREEN (-5950 4225);
DISPLAY INVISIBLE (-5950 4225);
FORCEPROP 1 LAST HDL_TAP TRUE
J 2
(-6275 4050);
DISPLAY 0.872340 (-6275 4050);
DISPLAY INVISIBLE (-6275 4050);
FORCEPROP 1 LAST PATH I280
J 2
(-5948 4175);
DISPLAY 0.872340 (-5948 4175);
PAINT GREEN (-5948 4175);
DISPLAY INVISIBLE (-5948 4175);
FORCEADD OFFPAGE..3
R 2
(-6650 6000);
FORCEPROP 2 LAST $XR0 92 
J 0
(-6899 6000);
DISPLAY 0.638298 (-6899 6000);
PAINT MONO (-6899 6000);
FORCEPROP 2 LAST PATH I281
J 0
(-6925 6050);
DISPLAY 1.021277 (-6925 6050);
DISPLAY INVISIBLE (-6925 6050);
FORCEPROP 1 LAST COMMENT_BODY TRUE
J 2
(-6600 5900);
DISPLAY 0.872340 (-6600 5900);
PAINT GREEN (-6600 5900);
DISPLAY INVISIBLE (-6600 5900);
FORCEPROP 1 LAST OFFPAGE TRUE
J 2
(-6975 5875);
DISPLAY 0.872340 (-6975 5875);
PAINT GREEN (-6975 5875);
DISPLAY INVISIBLE (-6975 5875);
FORCEPROP 2 LAST CDS_LIB standard
J 0
(-6650 6000);
DISPLAY INVISIBLE (-6650 6000);
FORCEADD OFFPAGE..3
R 2
(-6650 5950);
FORCEPROP 2 LAST $XR0 92 
J 0
(-6899 5950);
DISPLAY 0.638298 (-6899 5950);
PAINT MONO (-6899 5950);
FORCEPROP 2 LAST PATH I282
J 0
(-6925 6000);
DISPLAY 1.021277 (-6925 6000);
DISPLAY INVISIBLE (-6925 6000);
FORCEPROP 1 LAST COMMENT_BODY TRUE
J 2
(-6600 5850);
DISPLAY 0.872340 (-6600 5850);
PAINT GREEN (-6600 5850);
DISPLAY INVISIBLE (-6600 5850);
FORCEPROP 1 LAST OFFPAGE TRUE
J 2
(-6975 5825);
DISPLAY 0.872340 (-6975 5825);
PAINT GREEN (-6975 5825);
DISPLAY INVISIBLE (-6975 5825);
FORCEPROP 2 LAST CDS_LIB standard
J 0
(-6650 5950);
DISPLAY INVISIBLE (-6650 5950);
FORCEADD OFFPAGE..3
R 2
(-6650 4950);
FORCEPROP 2 LAST $XR0 92 
J 0
(-6899 4950);
DISPLAY 0.638298 (-6899 4950);
PAINT MONO (-6899 4950);
FORCEPROP 2 LAST PATH I283
J 0
(-6925 5000);
DISPLAY 1.021277 (-6925 5000);
DISPLAY INVISIBLE (-6925 5000);
FORCEPROP 1 LAST COMMENT_BODY TRUE
J 2
(-6600 4850);
DISPLAY 0.872340 (-6600 4850);
PAINT GREEN (-6600 4850);
DISPLAY INVISIBLE (-6600 4850);
FORCEPROP 1 LAST OFFPAGE TRUE
J 2
(-6975 4825);
DISPLAY 0.872340 (-6975 4825);
PAINT GREEN (-6975 4825);
DISPLAY INVISIBLE (-6975 4825);
FORCEPROP 2 LAST CDS_LIB standard
J 0
(-6650 4950);
DISPLAY INVISIBLE (-6650 4950);
FORCEADD OFFPAGE..3
R 2
(-6650 4900);
FORCEPROP 2 LAST $XR0 92 
J 0
(-6899 4900);
DISPLAY 0.638298 (-6899 4900);
PAINT MONO (-6899 4900);
FORCEPROP 2 LAST PATH I284
J 0
(-6925 4950);
DISPLAY 1.021277 (-6925 4950);
DISPLAY INVISIBLE (-6925 4950);
FORCEPROP 1 LAST COMMENT_BODY TRUE
J 2
(-6600 4800);
DISPLAY 0.872340 (-6600 4800);
PAINT GREEN (-6600 4800);
DISPLAY INVISIBLE (-6600 4800);
FORCEPROP 1 LAST OFFPAGE TRUE
J 2
(-6975 4775);
DISPLAY 0.872340 (-6975 4775);
PAINT GREEN (-6975 4775);
DISPLAY INVISIBLE (-6975 4775);
FORCEPROP 2 LAST CDS_LIB standard
J 0
(-6650 4900);
DISPLAY INVISIBLE (-6650 4900);
FORCEADD TAP..1
R 2
(-5750 4025);
FORCEPROP 3 LASTPIN (-5700 4025) SIG_NAME M_H_CPU0_SB_DQS_DP<9>
J 0
(-5690 4035);
DISPLAY 0.659574 (-5690 4035);
PAINT MONO (-5690 4035);
DISPLAY INVISIBLE (-5690 4035);
FORCEPROP 1 LASTPIN (-5700 4025) BN 9
J 2
(-5688 4033);
DISPLAY 0.489362 (-5688 4033);
PAINT GREEN (-5688 4033);
FORCEPROP 2 LAST CDS_LIB mstr_standard
J 2
(-5750 4025);
DISPLAY 0.723404 (-5750 4025);
PAINT MONO (-5750 4025);
DISPLAY INVISIBLE (-5750 4025);
FORCEPROP 1 LAST BODY_TYPE PLUMBING
J 2
(-5750 4075);
DISPLAY 0.872340 (-5750 4075);
PAINT GREEN (-5750 4075);
DISPLAY INVISIBLE (-5750 4075);
FORCEPROP 1 LAST HDL_TAP TRUE
J 2
(-6075 3900);
DISPLAY 0.872340 (-6075 3900);
DISPLAY INVISIBLE (-6075 3900);
FORCEPROP 1 LAST PATH I285
J 2
(-5748 4025);
DISPLAY 0.872340 (-5748 4025);
PAINT GREEN (-5748 4025);
DISPLAY INVISIBLE (-5748 4025);
FORCEADD TAP..1
R 2
(-5950 4075);
FORCEPROP 3 LASTPIN (-5900 4075) SIG_NAME M_H_CPU0_SB_DQS_DN<8>
J 0
(-5890 4085);
DISPLAY 0.659574 (-5890 4085);
PAINT MONO (-5890 4085);
DISPLAY INVISIBLE (-5890 4085);
FORCEPROP 1 LASTPIN (-5900 4075) BN 8
J 2
(-5888 4083);
DISPLAY 0.489362 (-5888 4083);
PAINT GREEN (-5888 4083);
FORCEPROP 2 LAST CDS_LIB mstr_standard
J 2
(-5950 4075);
DISPLAY 0.723404 (-5950 4075);
PAINT MONO (-5950 4075);
DISPLAY INVISIBLE (-5950 4075);
FORCEPROP 1 LAST BODY_TYPE PLUMBING
J 2
(-5950 4125);
DISPLAY 0.872340 (-5950 4125);
PAINT GREEN (-5950 4125);
DISPLAY INVISIBLE (-5950 4125);
FORCEPROP 1 LAST HDL_TAP TRUE
J 2
(-6275 3950);
DISPLAY 0.872340 (-6275 3950);
DISPLAY INVISIBLE (-6275 3950);
FORCEPROP 1 LAST PATH I286
J 2
(-5948 4075);
DISPLAY 0.872340 (-5948 4075);
PAINT GREEN (-5948 4075);
DISPLAY INVISIBLE (-5948 4075);
FORCEADD TAP..1
R 2
(-5950 3975);
FORCEPROP 3 LASTPIN (-5900 3975) SIG_NAME M_H_CPU0_SB_DQS_DN<9>
J 0
(-5890 3985);
DISPLAY 0.659574 (-5890 3985);
PAINT MONO (-5890 3985);
DISPLAY INVISIBLE (-5890 3985);
FORCEPROP 1 LASTPIN (-5900 3975) BN 9
J 2
(-5888 3983);
DISPLAY 0.489362 (-5888 3983);
PAINT GREEN (-5888 3983);
FORCEPROP 2 LAST CDS_LIB mstr_standard
J 2
(-5950 3975);
DISPLAY 0.723404 (-5950 3975);
PAINT MONO (-5950 3975);
DISPLAY INVISIBLE (-5950 3975);
FORCEPROP 1 LAST BODY_TYPE PLUMBING
J 2
(-5950 4025);
DISPLAY 0.872340 (-5950 4025);
PAINT GREEN (-5950 4025);
DISPLAY INVISIBLE (-5950 4025);
FORCEPROP 1 LAST HDL_TAP TRUE
J 2
(-6275 3850);
DISPLAY 0.872340 (-6275 3850);
DISPLAY INVISIBLE (-6275 3850);
FORCEPROP 1 LAST PATH I287
J 2
(-5948 3975);
DISPLAY 0.872340 (-5948 3975);
PAINT GREEN (-5948 3975);
DISPLAY INVISIBLE (-5948 3975);
FORCEADD TAP..1
R 2
(-5950 3825);
FORCEPROP 3 LASTPIN (-5900 3825) SIG_NAME M_H_CPU0_SA_CA<0>
J 0
(-5890 3835);
DISPLAY 0.659574 (-5890 3835);
PAINT MONO (-5890 3835);
DISPLAY INVISIBLE (-5890 3835);
FORCEPROP 1 LASTPIN (-5900 3825) BN 0
J 2
(-5888 3833);
DISPLAY 0.489362 (-5888 3833);
PAINT GREEN (-5888 3833);
FORCEPROP 2 LAST CDS_LIB mstr_standard
J 0
(-5950 3825);
DISPLAY 0.723404 (-5950 3825);
PAINT MONO (-5950 3825);
DISPLAY INVISIBLE (-5950 3825);
FORCEPROP 1 LAST BODY_TYPE PLUMBING
J 2
(-5950 3875);
DISPLAY 0.872340 (-5950 3875);
PAINT GREEN (-5950 3875);
DISPLAY INVISIBLE (-5950 3875);
FORCEPROP 1 LAST HDL_TAP TRUE
J 2
(-6275 3700);
DISPLAY 0.872340 (-6275 3700);
DISPLAY INVISIBLE (-6275 3700);
FORCEPROP 1 LAST PATH I288
J 2
(-5948 3825);
DISPLAY 0.872340 (-5948 3825);
PAINT GREEN (-5948 3825);
DISPLAY INVISIBLE (-5948 3825);
FORCEADD TAP..1
R 2
(-5950 3775);
FORCEPROP 3 LASTPIN (-5900 3775) SIG_NAME M_H_CPU0_SA_CA<1>
J 0
(-5890 3785);
DISPLAY 0.659574 (-5890 3785);
PAINT MONO (-5890 3785);
DISPLAY INVISIBLE (-5890 3785);
FORCEPROP 1 LASTPIN (-5900 3775) BN 1
J 2
(-5888 3783);
DISPLAY 0.489362 (-5888 3783);
PAINT GREEN (-5888 3783);
FORCEPROP 2 LAST CDS_LIB mstr_standard
J 0
(-5950 3775);
DISPLAY 0.723404 (-5950 3775);
PAINT MONO (-5950 3775);
DISPLAY INVISIBLE (-5950 3775);
FORCEPROP 1 LAST BODY_TYPE PLUMBING
J 2
(-5950 3825);
DISPLAY 0.872340 (-5950 3825);
PAINT GREEN (-5950 3825);
DISPLAY INVISIBLE (-5950 3825);
FORCEPROP 1 LAST HDL_TAP TRUE
J 2
(-6275 3650);
DISPLAY 0.872340 (-6275 3650);
DISPLAY INVISIBLE (-6275 3650);
FORCEPROP 1 LAST PATH I289
J 2
(-5948 3775);
DISPLAY 0.872340 (-5948 3775);
PAINT GREEN (-5948 3775);
DISPLAY INVISIBLE (-5948 3775);
FORCEADD TAP..1
R 2
(-5950 3725);
FORCEPROP 3 LASTPIN (-5900 3725) SIG_NAME M_H_CPU0_SA_CA<2>
J 0
(-5890 3735);
DISPLAY 0.659574 (-5890 3735);
PAINT MONO (-5890 3735);
DISPLAY INVISIBLE (-5890 3735);
FORCEPROP 1 LASTPIN (-5900 3725) BN 2
J 2
(-5888 3733);
DISPLAY 0.489362 (-5888 3733);
PAINT GREEN (-5888 3733);
FORCEPROP 2 LAST CDS_LIB mstr_standard
J 0
(-5950 3725);
DISPLAY 0.723404 (-5950 3725);
PAINT MONO (-5950 3725);
DISPLAY INVISIBLE (-5950 3725);
FORCEPROP 1 LAST BODY_TYPE PLUMBING
J 2
(-5950 3775);
DISPLAY 0.872340 (-5950 3775);
PAINT GREEN (-5950 3775);
DISPLAY INVISIBLE (-5950 3775);
FORCEPROP 1 LAST HDL_TAP TRUE
J 2
(-6275 3600);
DISPLAY 0.872340 (-6275 3600);
DISPLAY INVISIBLE (-6275 3600);
FORCEPROP 1 LAST PATH I290
J 2
(-5948 3725);
DISPLAY 0.872340 (-5948 3725);
PAINT GREEN (-5948 3725);
DISPLAY INVISIBLE (-5948 3725);
FORCEADD TAP..1
R 2
(-5950 3675);
FORCEPROP 3 LASTPIN (-5900 3675) SIG_NAME M_H_CPU0_SA_CA<3>
J 0
(-5890 3685);
DISPLAY 0.659574 (-5890 3685);
PAINT MONO (-5890 3685);
DISPLAY INVISIBLE (-5890 3685);
FORCEPROP 1 LASTPIN (-5900 3675) BN 3
J 2
(-5888 3683);
DISPLAY 0.489362 (-5888 3683);
PAINT GREEN (-5888 3683);
FORCEPROP 2 LAST CDS_LIB mstr_standard
J 0
(-5950 3675);
DISPLAY 0.723404 (-5950 3675);
PAINT MONO (-5950 3675);
DISPLAY INVISIBLE (-5950 3675);
FORCEPROP 1 LAST BODY_TYPE PLUMBING
J 2
(-5950 3725);
DISPLAY 0.872340 (-5950 3725);
PAINT GREEN (-5950 3725);
DISPLAY INVISIBLE (-5950 3725);
FORCEPROP 1 LAST HDL_TAP TRUE
J 2
(-6275 3550);
DISPLAY 0.872340 (-6275 3550);
DISPLAY INVISIBLE (-6275 3550);
FORCEPROP 1 LAST PATH I291
J 2
(-5948 3675);
DISPLAY 0.872340 (-5948 3675);
PAINT GREEN (-5948 3675);
DISPLAY INVISIBLE (-5948 3675);
FORCEADD TAP..1
R 2
(-5950 3625);
FORCEPROP 3 LASTPIN (-5900 3625) SIG_NAME M_H_CPU0_SA_CA<4>
J 0
(-5890 3635);
DISPLAY 0.659574 (-5890 3635);
PAINT MONO (-5890 3635);
DISPLAY INVISIBLE (-5890 3635);
FORCEPROP 1 LASTPIN (-5900 3625) BN 4
J 2
(-5888 3633);
DISPLAY 0.489362 (-5888 3633);
PAINT GREEN (-5888 3633);
FORCEPROP 2 LAST CDS_LIB mstr_standard
J 0
(-5950 3625);
DISPLAY 0.723404 (-5950 3625);
PAINT MONO (-5950 3625);
DISPLAY INVISIBLE (-5950 3625);
FORCEPROP 1 LAST BODY_TYPE PLUMBING
J 2
(-5950 3675);
DISPLAY 0.872340 (-5950 3675);
PAINT GREEN (-5950 3675);
DISPLAY INVISIBLE (-5950 3675);
FORCEPROP 1 LAST HDL_TAP TRUE
J 2
(-6275 3500);
DISPLAY 0.872340 (-6275 3500);
DISPLAY INVISIBLE (-6275 3500);
FORCEPROP 1 LAST PATH I292
J 2
(-5948 3625);
DISPLAY 0.872340 (-5948 3625);
PAINT GREEN (-5948 3625);
DISPLAY INVISIBLE (-5948 3625);
FORCEADD TAP..1
R 2
(-5950 3575);
FORCEPROP 3 LASTPIN (-5900 3575) SIG_NAME M_H_CPU0_SA_CA<5>
J 0
(-5890 3585);
DISPLAY 0.659574 (-5890 3585);
PAINT MONO (-5890 3585);
DISPLAY INVISIBLE (-5890 3585);
FORCEPROP 1 LASTPIN (-5900 3575) BN 5
J 2
(-5888 3583);
DISPLAY 0.489362 (-5888 3583);
PAINT GREEN (-5888 3583);
FORCEPROP 2 LAST CDS_LIB mstr_standard
J 0
(-5950 3575);
DISPLAY 0.723404 (-5950 3575);
PAINT MONO (-5950 3575);
DISPLAY INVISIBLE (-5950 3575);
FORCEPROP 1 LAST BODY_TYPE PLUMBING
J 2
(-5950 3625);
DISPLAY 0.872340 (-5950 3625);
PAINT GREEN (-5950 3625);
DISPLAY INVISIBLE (-5950 3625);
FORCEPROP 1 LAST HDL_TAP TRUE
J 2
(-6275 3450);
DISPLAY 0.872340 (-6275 3450);
DISPLAY INVISIBLE (-6275 3450);
FORCEPROP 1 LAST PATH I293
J 2
(-5948 3575);
DISPLAY 0.872340 (-5948 3575);
PAINT GREEN (-5948 3575);
DISPLAY INVISIBLE (-5948 3575);
FORCEADD TAP..1
R 2
(-5950 3525);
FORCEPROP 3 LASTPIN (-5900 3525) SIG_NAME M_H_CPU0_SA_CA<6>
J 0
(-5890 3535);
DISPLAY 0.659574 (-5890 3535);
PAINT MONO (-5890 3535);
DISPLAY INVISIBLE (-5890 3535);
FORCEPROP 1 LASTPIN (-5900 3525) BN 6
J 2
(-5888 3533);
DISPLAY 0.489362 (-5888 3533);
PAINT GREEN (-5888 3533);
FORCEPROP 2 LAST CDS_LIB mstr_standard
J 0
(-5950 3525);
DISPLAY 0.723404 (-5950 3525);
PAINT MONO (-5950 3525);
DISPLAY INVISIBLE (-5950 3525);
FORCEPROP 1 LAST BODY_TYPE PLUMBING
J 2
(-5950 3575);
DISPLAY 0.872340 (-5950 3575);
PAINT GREEN (-5950 3575);
DISPLAY INVISIBLE (-5950 3575);
FORCEPROP 1 LAST HDL_TAP TRUE
J 2
(-6275 3400);
DISPLAY 0.872340 (-6275 3400);
DISPLAY INVISIBLE (-6275 3400);
FORCEPROP 1 LAST PATH I294
J 2
(-5948 3525);
DISPLAY 0.872340 (-5948 3525);
PAINT GREEN (-5948 3525);
DISPLAY INVISIBLE (-5948 3525);
FORCEADD TAP..1
R 2
(-5950 3325);
FORCEPROP 3 LASTPIN (-5900 3325) SIG_NAME M_H_CPU0_SB_CA<2>
J 0
(-5890 3335);
DISPLAY 0.659574 (-5890 3335);
PAINT MONO (-5890 3335);
DISPLAY INVISIBLE (-5890 3335);
FORCEPROP 1 LASTPIN (-5900 3325) BN 2
J 2
(-5888 3333);
DISPLAY 0.489362 (-5888 3333);
PAINT GREEN (-5888 3333);
FORCEPROP 2 LAST CDS_LIB mstr_standard
J 0
(-5950 3325);
DISPLAY 0.723404 (-5950 3325);
PAINT MONO (-5950 3325);
DISPLAY INVISIBLE (-5950 3325);
FORCEPROP 1 LAST BODY_TYPE PLUMBING
J 2
(-5950 3375);
DISPLAY 0.872340 (-5950 3375);
PAINT GREEN (-5950 3375);
DISPLAY INVISIBLE (-5950 3375);
FORCEPROP 1 LAST HDL_TAP TRUE
J 2
(-6275 3200);
DISPLAY 0.872340 (-6275 3200);
DISPLAY INVISIBLE (-6275 3200);
FORCEPROP 1 LAST PATH I295
J 2
(-5948 3325);
DISPLAY 0.872340 (-5948 3325);
PAINT GREEN (-5948 3325);
DISPLAY INVISIBLE (-5948 3325);
FORCEADD TAP..1
R 2
(-5950 3425);
FORCEPROP 3 LASTPIN (-5900 3425) SIG_NAME M_H_CPU0_SB_CA<0>
J 0
(-5890 3435);
DISPLAY 0.659574 (-5890 3435);
PAINT MONO (-5890 3435);
DISPLAY INVISIBLE (-5890 3435);
FORCEPROP 1 LASTPIN (-5900 3425) BN 0
J 2
(-5888 3433);
DISPLAY 0.489362 (-5888 3433);
PAINT GREEN (-5888 3433);
FORCEPROP 2 LAST CDS_LIB mstr_standard
J 0
(-5950 3425);
DISPLAY 0.723404 (-5950 3425);
PAINT MONO (-5950 3425);
DISPLAY INVISIBLE (-5950 3425);
FORCEPROP 1 LAST BODY_TYPE PLUMBING
J 2
(-5950 3475);
DISPLAY 0.872340 (-5950 3475);
PAINT GREEN (-5950 3475);
DISPLAY INVISIBLE (-5950 3475);
FORCEPROP 1 LAST HDL_TAP TRUE
J 2
(-6275 3300);
DISPLAY 0.872340 (-6275 3300);
DISPLAY INVISIBLE (-6275 3300);
FORCEPROP 1 LAST PATH I296
J 2
(-5948 3425);
DISPLAY 0.872340 (-5948 3425);
PAINT GREEN (-5948 3425);
DISPLAY INVISIBLE (-5948 3425);
FORCEADD TAP..1
R 2
(-5950 3375);
FORCEPROP 3 LASTPIN (-5900 3375) SIG_NAME M_H_CPU0_SB_CA<1>
J 0
(-5890 3385);
DISPLAY 0.659574 (-5890 3385);
PAINT MONO (-5890 3385);
DISPLAY INVISIBLE (-5890 3385);
FORCEPROP 1 LASTPIN (-5900 3375) BN 1
J 2
(-5888 3383);
DISPLAY 0.489362 (-5888 3383);
PAINT GREEN (-5888 3383);
FORCEPROP 2 LAST CDS_LIB mstr_standard
J 0
(-5950 3375);
DISPLAY 0.723404 (-5950 3375);
PAINT MONO (-5950 3375);
DISPLAY INVISIBLE (-5950 3375);
FORCEPROP 1 LAST BODY_TYPE PLUMBING
J 2
(-5950 3425);
DISPLAY 0.872340 (-5950 3425);
PAINT GREEN (-5950 3425);
DISPLAY INVISIBLE (-5950 3425);
FORCEPROP 1 LAST HDL_TAP TRUE
J 2
(-6275 3250);
DISPLAY 0.872340 (-6275 3250);
DISPLAY INVISIBLE (-6275 3250);
FORCEPROP 1 LAST PATH I297
J 2
(-5948 3375);
DISPLAY 0.872340 (-5948 3375);
PAINT GREEN (-5948 3375);
DISPLAY INVISIBLE (-5948 3375);
FORCEADD TAP..1
R 2
(-5950 3275);
FORCEPROP 3 LASTPIN (-5900 3275) SIG_NAME M_H_CPU0_SB_CA<3>
J 0
(-5890 3285);
DISPLAY 0.659574 (-5890 3285);
PAINT MONO (-5890 3285);
DISPLAY INVISIBLE (-5890 3285);
FORCEPROP 1 LASTPIN (-5900 3275) BN 3
J 2
(-5888 3283);
DISPLAY 0.489362 (-5888 3283);
PAINT GREEN (-5888 3283);
FORCEPROP 2 LAST CDS_LIB mstr_standard
J 0
(-5950 3275);
DISPLAY 0.723404 (-5950 3275);
PAINT MONO (-5950 3275);
DISPLAY INVISIBLE (-5950 3275);
FORCEPROP 1 LAST BODY_TYPE PLUMBING
J 2
(-5950 3325);
DISPLAY 0.872340 (-5950 3325);
PAINT GREEN (-5950 3325);
DISPLAY INVISIBLE (-5950 3325);
FORCEPROP 1 LAST HDL_TAP TRUE
J 2
(-6275 3150);
DISPLAY 0.872340 (-6275 3150);
DISPLAY INVISIBLE (-6275 3150);
FORCEPROP 1 LAST PATH I298
J 2
(-5948 3275);
DISPLAY 0.872340 (-5948 3275);
PAINT GREEN (-5948 3275);
DISPLAY INVISIBLE (-5948 3275);
FORCEADD TAP..1
R 2
(-5950 3225);
FORCEPROP 3 LASTPIN (-5900 3225) SIG_NAME M_H_CPU0_SB_CA<4>
J 0
(-5890 3235);
DISPLAY 0.659574 (-5890 3235);
PAINT MONO (-5890 3235);
DISPLAY INVISIBLE (-5890 3235);
FORCEPROP 1 LASTPIN (-5900 3225) BN 4
J 2
(-5888 3233);
DISPLAY 0.489362 (-5888 3233);
PAINT GREEN (-5888 3233);
FORCEPROP 2 LAST CDS_LIB mstr_standard
J 0
(-5950 3225);
DISPLAY 0.723404 (-5950 3225);
PAINT MONO (-5950 3225);
DISPLAY INVISIBLE (-5950 3225);
FORCEPROP 1 LAST BODY_TYPE PLUMBING
J 2
(-5950 3275);
DISPLAY 0.872340 (-5950 3275);
PAINT GREEN (-5950 3275);
DISPLAY INVISIBLE (-5950 3275);
FORCEPROP 1 LAST HDL_TAP TRUE
J 2
(-6275 3100);
DISPLAY 0.872340 (-6275 3100);
DISPLAY INVISIBLE (-6275 3100);
FORCEPROP 1 LAST PATH I299
J 2
(-5948 3225);
DISPLAY 0.872340 (-5948 3225);
PAINT GREEN (-5948 3225);
DISPLAY INVISIBLE (-5948 3225);
FORCEADD TAP..1
R 2
(-5950 3125);
FORCEPROP 3 LASTPIN (-5900 3125) SIG_NAME M_H_CPU0_SB_CA<6>
J 0
(-5890 3135);
DISPLAY 0.659574 (-5890 3135);
PAINT MONO (-5890 3135);
DISPLAY INVISIBLE (-5890 3135);
FORCEPROP 1 LASTPIN (-5900 3125) BN 6
J 2
(-5888 3133);
DISPLAY 0.489362 (-5888 3133);
PAINT GREEN (-5888 3133);
FORCEPROP 2 LAST CDS_LIB mstr_standard
J 0
(-5950 3125);
DISPLAY 0.723404 (-5950 3125);
PAINT MONO (-5950 3125);
DISPLAY INVISIBLE (-5950 3125);
FORCEPROP 1 LAST BODY_TYPE PLUMBING
J 2
(-5950 3175);
DISPLAY 0.872340 (-5950 3175);
PAINT GREEN (-5950 3175);
DISPLAY INVISIBLE (-5950 3175);
FORCEPROP 1 LAST HDL_TAP TRUE
J 2
(-6275 3000);
DISPLAY 0.872340 (-6275 3000);
DISPLAY INVISIBLE (-6275 3000);
FORCEPROP 1 LAST PATH I300
J 2
(-5948 3125);
DISPLAY 0.872340 (-5948 3125);
PAINT GREEN (-5948 3125);
DISPLAY INVISIBLE (-5948 3125);
FORCEADD TAP..1
R 2
(-5950 3175);
FORCEPROP 3 LASTPIN (-5900 3175) SIG_NAME M_H_CPU0_SB_CA<5>
J 0
(-5890 3185);
DISPLAY 0.659574 (-5890 3185);
PAINT MONO (-5890 3185);
DISPLAY INVISIBLE (-5890 3185);
FORCEPROP 1 LASTPIN (-5900 3175) BN 5
J 2
(-5888 3183);
DISPLAY 0.489362 (-5888 3183);
PAINT GREEN (-5888 3183);
FORCEPROP 2 LAST CDS_LIB mstr_standard
J 0
(-5950 3175);
DISPLAY 0.723404 (-5950 3175);
PAINT MONO (-5950 3175);
DISPLAY INVISIBLE (-5950 3175);
FORCEPROP 1 LAST BODY_TYPE PLUMBING
J 2
(-5950 3225);
DISPLAY 0.872340 (-5950 3225);
PAINT GREEN (-5950 3225);
DISPLAY INVISIBLE (-5950 3225);
FORCEPROP 1 LAST HDL_TAP TRUE
J 2
(-6275 3050);
DISPLAY 0.872340 (-6275 3050);
DISPLAY INVISIBLE (-6275 3050);
FORCEPROP 1 LAST PATH I301
J 2
(-5948 3175);
DISPLAY 0.872340 (-5948 3175);
PAINT GREEN (-5948 3175);
DISPLAY INVISIBLE (-5948 3175);
FORCEADD OFFPAGE..2
R 2
(-6550 3850);
FORCEPROP 2 LAST $XR0 92 
J 0
(-6774 3850);
DISPLAY 0.638298 (-6774 3850);
PAINT MONO (-6774 3850);
FORCEPROP 2 LAST PATH I302
J 0
(-6800 3900);
DISPLAY 1.021277 (-6800 3900);
DISPLAY INVISIBLE (-6800 3900);
FORCEPROP 1 LAST COMMENT_BODY TRUE
J 2
(-6505 3755);
DISPLAY 0.872340 (-6505 3755);
PAINT GREEN (-6505 3755);
DISPLAY INVISIBLE (-6505 3755);
FORCEPROP 1 LAST OFFPAGE TRUE
J 2
(-6875 3725);
DISPLAY 0.872340 (-6875 3725);
PAINT GREEN (-6875 3725);
DISPLAY INVISIBLE (-6875 3725);
FORCEPROP 2 LAST CDS_LIB standard
J 0
(-6550 3850);
DISPLAY INVISIBLE (-6550 3850);
FORCEADD OFFPAGE..2
R 2
(-6550 3450);
FORCEPROP 2 LAST $XR0 92 
J 0
(-6774 3450);
DISPLAY 0.638298 (-6774 3450);
PAINT MONO (-6774 3450);
FORCEPROP 2 LAST PATH I303
J 0
(-6800 3500);
DISPLAY 1.021277 (-6800 3500);
DISPLAY INVISIBLE (-6800 3500);
FORCEPROP 1 LAST COMMENT_BODY TRUE
J 2
(-6505 3355);
DISPLAY 0.872340 (-6505 3355);
PAINT GREEN (-6505 3355);
DISPLAY INVISIBLE (-6505 3355);
FORCEPROP 1 LAST OFFPAGE TRUE
J 2
(-6875 3325);
DISPLAY 0.872340 (-6875 3325);
PAINT GREEN (-6875 3325);
DISPLAY INVISIBLE (-6875 3325);
FORCEPROP 2 LAST CDS_LIB standard
J 0
(-6550 3450);
DISPLAY INVISIBLE (-6550 3450);
FORCEADD OFFPAGE..2
R 2
(-6550 2975);
FORCEPROP 2 LAST $XR0 92 
J 0
(-6774 2975);
DISPLAY 0.638298 (-6774 2975);
PAINT MONO (-6774 2975);
FORCEPROP 2 LAST PATH I304
J 0
(-6800 3025);
DISPLAY 1.021277 (-6800 3025);
DISPLAY INVISIBLE (-6800 3025);
FORCEPROP 1 LAST COMMENT_BODY TRUE
J 2
(-6505 2880);
DISPLAY 0.872340 (-6505 2880);
PAINT GREEN (-6505 2880);
DISPLAY INVISIBLE (-6505 2880);
FORCEPROP 1 LAST OFFPAGE TRUE
J 2
(-6875 2850);
DISPLAY 0.872340 (-6875 2850);
PAINT GREEN (-6875 2850);
DISPLAY INVISIBLE (-6875 2850);
FORCEPROP 2 LAST CDS_LIB standard
J 0
(-6550 2975);
DISPLAY INVISIBLE (-6550 2975);
FORCEADD OFFPAGE..2
R 2
(-6550 2925);
FORCEPROP 2 LAST $XR0 92 
J 0
(-6774 2925);
DISPLAY 0.638298 (-6774 2925);
PAINT MONO (-6774 2925);
FORCEPROP 2 LAST PATH I305
J 0
(-6800 2975);
DISPLAY 1.021277 (-6800 2975);
DISPLAY INVISIBLE (-6800 2975);
FORCEPROP 1 LAST COMMENT_BODY TRUE
J 2
(-6505 2830);
DISPLAY 0.872340 (-6505 2830);
PAINT GREEN (-6505 2830);
DISPLAY INVISIBLE (-6505 2830);
FORCEPROP 1 LAST OFFPAGE TRUE
J 2
(-6875 2800);
DISPLAY 0.872340 (-6875 2800);
PAINT GREEN (-6875 2800);
DISPLAY INVISIBLE (-6875 2800);
FORCEPROP 2 LAST CDS_LIB standard
J 0
(-6550 2925);
DISPLAY INVISIBLE (-6550 2925);
FORCEADD OFFPAGE..2
R 2
(-6550 2825);
FORCEPROP 2 LAST $XR0 92 
J 0
(-6774 2825);
DISPLAY 0.638298 (-6774 2825);
PAINT MONO (-6774 2825);
FORCEPROP 2 LAST PATH I306
J 0
(-6800 2875);
DISPLAY 1.021277 (-6800 2875);
DISPLAY INVISIBLE (-6800 2875);
FORCEPROP 1 LAST COMMENT_BODY TRUE
J 2
(-6505 2730);
DISPLAY 0.872340 (-6505 2730);
PAINT GREEN (-6505 2730);
DISPLAY INVISIBLE (-6505 2730);
FORCEPROP 1 LAST OFFPAGE TRUE
J 2
(-6875 2700);
DISPLAY 0.872340 (-6875 2700);
PAINT GREEN (-6875 2700);
DISPLAY INVISIBLE (-6875 2700);
FORCEPROP 2 LAST CDS_LIB standard
J 0
(-6550 2825);
DISPLAY INVISIBLE (-6550 2825);
FORCEADD OFFPAGE..2
R 2
(-6550 2775);
FORCEPROP 2 LAST $XR0 92 
J 0
(-6774 2775);
DISPLAY 0.638298 (-6774 2775);
PAINT MONO (-6774 2775);
FORCEPROP 2 LAST PATH I307
J 0
(-6800 2825);
DISPLAY 1.021277 (-6800 2825);
DISPLAY INVISIBLE (-6800 2825);
FORCEPROP 1 LAST COMMENT_BODY TRUE
J 2
(-6505 2680);
DISPLAY 0.872340 (-6505 2680);
PAINT GREEN (-6505 2680);
DISPLAY INVISIBLE (-6505 2680);
FORCEPROP 1 LAST OFFPAGE TRUE
J 2
(-6875 2650);
DISPLAY 0.872340 (-6875 2650);
PAINT GREEN (-6875 2650);
DISPLAY INVISIBLE (-6875 2650);
FORCEPROP 2 LAST CDS_LIB standard
J 0
(-6550 2775);
DISPLAY INVISIBLE (-6550 2775);
FORCEADD OFFPAGE..1
(-6550 2675);
FORCEPROP 2 LAST $XR0 92 
J 0
(-6801 2675);
DISPLAY 0.638298 (-6801 2675);
PAINT MONO (-6801 2675);
FORCEPROP 2 LAST PATH I308
J 0
(-6825 2725);
DISPLAY 1.021277 (-6825 2725);
DISPLAY INVISIBLE (-6825 2725);
FORCEPROP 1 LAST COMMENT_BODY TRUE
J 0
(-6425 2575);
DISPLAY 0.872340 (-6425 2575);
PAINT GREEN (-6425 2575);
DISPLAY INVISIBLE (-6425 2575);
FORCEPROP 1 LAST OFFPAGE TRUE
J 0
(-6225 2550);
DISPLAY 0.872340 (-6225 2550);
PAINT GREEN (-6225 2550);
DISPLAY INVISIBLE (-6225 2550);
FORCEPROP 2 LAST CDS_LIB standard
J 0
(-6550 2675);
DISPLAY INVISIBLE (-6550 2675);
FORCEADD OFFPAGE..5
(-6550 2575);
FORCEPROP 2 LAST $XR0 92 
J 0
(-6774 2575);
DISPLAY 0.638298 (-6774 2575);
PAINT MONO (-6774 2575);
FORCEPROP 2 LAST PATH I309
J 0
(-6800 2625);
DISPLAY 1.021277 (-6800 2625);
DISPLAY INVISIBLE (-6800 2625);
FORCEPROP 1 LAST COMMENT_BODY TRUE
J 0
(-6450 2500);
DISPLAY 0.872340 (-6450 2500);
PAINT GREEN (-6450 2500);
DISPLAY INVISIBLE (-6450 2500);
FORCEPROP 1 LAST OFFPAGE TRUE
J 0
(-6225 2450);
DISPLAY 0.872340 (-6225 2450);
PAINT GREEN (-6225 2450);
DISPLAY INVISIBLE (-6225 2450);
FORCEPROP 2 LAST CDS_LIB mstr_standard
J 0
(-6550 2575);
DISPLAY INVISIBLE (-6550 2575);
FORCEADD OFFPAGE..2
R 2
(-6550 2425);
FORCEPROP 2 LAST $XR0 92 
J 0
(-6774 2425);
DISPLAY 0.638298 (-6774 2425);
PAINT MONO (-6774 2425);
FORCEPROP 2 LAST PATH I310
J 0
(-6800 2475);
DISPLAY 1.021277 (-6800 2475);
DISPLAY INVISIBLE (-6800 2475);
FORCEPROP 1 LAST COMMENT_BODY TRUE
J 2
(-6505 2330);
DISPLAY 0.872340 (-6505 2330);
PAINT GREEN (-6505 2330);
DISPLAY INVISIBLE (-6505 2330);
FORCEPROP 1 LAST OFFPAGE TRUE
J 2
(-6875 2300);
DISPLAY 0.872340 (-6875 2300);
PAINT GREEN (-6875 2300);
DISPLAY INVISIBLE (-6875 2300);
FORCEPROP 2 LAST CDS_LIB standard
J 0
(-6550 2425);
DISPLAY INVISIBLE (-6550 2425);
FORCEADD OFFPAGE..2
R 2
(-6550 2475);
FORCEPROP 2 LAST $XR0 92 
J 0
(-6774 2475);
DISPLAY 0.638298 (-6774 2475);
PAINT MONO (-6774 2475);
FORCEPROP 2 LAST PATH I311
J 0
(-6800 2525);
DISPLAY 1.021277 (-6800 2525);
DISPLAY INVISIBLE (-6800 2525);
FORCEPROP 1 LAST COMMENT_BODY TRUE
J 2
(-6505 2380);
DISPLAY 0.872340 (-6505 2380);
PAINT GREEN (-6505 2380);
DISPLAY INVISIBLE (-6505 2380);
FORCEPROP 1 LAST OFFPAGE TRUE
J 2
(-6875 2350);
DISPLAY 0.872340 (-6875 2350);
PAINT GREEN (-6875 2350);
DISPLAY INVISIBLE (-6875 2350);
FORCEPROP 2 LAST CDS_LIB standard
J 0
(-6550 2475);
DISPLAY INVISIBLE (-6550 2475);
FORCEADD OFFPAGE..1
(-6550 2325);
FORCEPROP 2 LAST $XR0 92 
J 0
(-6801 2325);
DISPLAY 0.638298 (-6801 2325);
PAINT MONO (-6801 2325);
FORCEPROP 2 LAST PATH I312
J 0
(-6825 2375);
DISPLAY 1.021277 (-6825 2375);
DISPLAY INVISIBLE (-6825 2375);
FORCEPROP 1 LAST COMMENT_BODY TRUE
J 0
(-6425 2225);
DISPLAY 0.872340 (-6425 2225);
PAINT GREEN (-6425 2225);
DISPLAY INVISIBLE (-6425 2225);
FORCEPROP 1 LAST OFFPAGE TRUE
J 0
(-6225 2200);
DISPLAY 0.872340 (-6225 2200);
PAINT GREEN (-6225 2200);
DISPLAY INVISIBLE (-6225 2200);
FORCEPROP 2 LAST CDS_LIB standard
J 0
(-6550 2325);
DISPLAY INVISIBLE (-6550 2325);
FORCEADD OFFPAGE..5
(-6550 2225);
FORCEPROP 2 LAST $XR0 92 
J 0
(-6774 2225);
DISPLAY 0.638298 (-6774 2225);
PAINT MONO (-6774 2225);
FORCEPROP 2 LAST PATH I313
J 0
(-6800 2275);
DISPLAY 1.021277 (-6800 2275);
DISPLAY INVISIBLE (-6800 2275);
FORCEPROP 1 LAST COMMENT_BODY TRUE
J 0
(-6450 2150);
DISPLAY 0.872340 (-6450 2150);
PAINT GREEN (-6450 2150);
DISPLAY INVISIBLE (-6450 2150);
FORCEPROP 1 LAST OFFPAGE TRUE
J 0
(-6225 2100);
DISPLAY 0.872340 (-6225 2100);
PAINT GREEN (-6225 2100);
DISPLAY INVISIBLE (-6225 2100);
FORCEPROP 2 LAST CDS_LIB standard
J 0
(-6550 2225);
DISPLAY INVISIBLE (-6550 2225);
FORCEADD Q_RES..1
(-6875 2125);
FORCEPROP 1 LAST LOCATION R382
J 0
(-7200 2125);
DISPLAY 0.489362 (-7200 2125);
PAINT SKYBLUE (-7200 2125);
FORCEPROP 0 LAST $SEC 1
J 0
(-7050 2175);
DISPLAY 0.680851 (-7050 2175);
PAINT MONO (-7050 2175);
DISPLAY INVISIBLE (-7050 2175);
FORCEPROP 0 LAST CDS_SEC 1
J 0
(-7050 2175);
DISPLAY 1.021277 (-7050 2175);
DISPLAY INVISIBLE (-7050 2175);
FORCEPROP 1 LASTPIN (-6975 2125) $PN 1
J 0
(-6963 2137);
DISPLAY 0.489362 (-6963 2137);
PAINT MONO (-6963 2137);
FORCEPROP 1 LASTPIN (-6775 2125) $PN 2
J 0
(-6813 2137);
DISPLAY 0.489362 (-6813 2137);
PAINT MONO (-6813 2137);
FORCEPROP 1 LAST TOLERANCE 1%
J 0
(-6600 2125);
DISPLAY 0.489362 (-6600 2125);
PAINT SKYBLUE (-6600 2125);
FORCEPROP 1 LAST VALUE 15   
J 2
(-6550 2125);
DISPLAY 0.489362 (-6550 2125);
PAINT SKYBLUE (-6550 2125);
FORCEPROP 1 LAST PART_NUMBER CS01502FB11
J 0
(-6775 2100);
DISPLAY 0.489362 (-6775 2100);
PAINT SKYBLUE (-6775 2100);
FORCEPROP 1 LAST PACK_TYPE 0402LF
J 0
(-7200 2100);
DISPLAY 0.489362 (-7200 2100);
PAINT SKYBLUE (-7200 2100);
FORCEPROP 2 LAST CDS_LIB pure_quanta
J 0
(-6875 2125);
DISPLAY INVISIBLE (-6875 2125);
FORCEPROP 1 LAST PATH I314
J 0
(-6925 2275);
DISPLAY 0.978723 (-6925 2275);
PAINT WHITE (-6925 2275);
DISPLAY INVISIBLE (-6925 2275);
FORCEPROP 1 LAST WATTAGE 1/16W
J 2
(-6650 2250);
DISPLAY 0.638298 (-6650 2250);
PAINT SKYBLUE (-6650 2250);
DISPLAY INVISIBLE (-6650 2250);
FORCEPROP 1 LAST MATERIAL CHIP
J 0
(-7000 2250);
DISPLAY 0.638298 (-7000 2250);
PAINT SKYBLUE (-7000 2250);
DISPLAY INVISIBLE (-7000 2250);
FORCEADD OFFPAGE..1
(-7750 2125);
FORCEPROP 2 LAST $XR0 92 
J 0
(-7971 2125);
DISPLAY 0.638298 (-7971 2125);
PAINT MONO (-7971 2125);
FORCEPROP 2 LAST PATH I315
J 0
(-8000 2175);
DISPLAY 1.021277 (-8000 2175);
DISPLAY INVISIBLE (-8000 2175);
FORCEPROP 1 LAST COMMENT_BODY TRUE
J 0
(-7625 2025);
DISPLAY 0.872340 (-7625 2025);
PAINT GREEN (-7625 2025);
DISPLAY INVISIBLE (-7625 2025);
FORCEPROP 1 LAST OFFPAGE TRUE
J 0
(-7425 2000);
DISPLAY 0.872340 (-7425 2000);
PAINT GREEN (-7425 2000);
DISPLAY INVISIBLE (-7425 2000);
FORCEPROP 2 LAST CDS_LIB mstr_standard
J 0
(-7750 2125);
DISPLAY INVISIBLE (-7750 2125);
FORCEADD OFFPAGE..5
(-6550 2025);
FORCEPROP 2 LAST $XR0 92 
J 0
(-6774 2025);
DISPLAY 0.638298 (-6774 2025);
PAINT MONO (-6774 2025);
FORCEPROP 2 LAST PATH I316
J 0
(-6800 2075);
DISPLAY 1.021277 (-6800 2075);
DISPLAY INVISIBLE (-6800 2075);
FORCEPROP 1 LAST COMMENT_BODY TRUE
J 0
(-6450 1950);
DISPLAY 0.872340 (-6450 1950);
PAINT GREEN (-6450 1950);
DISPLAY INVISIBLE (-6450 1950);
FORCEPROP 1 LAST OFFPAGE TRUE
J 0
(-6225 1900);
DISPLAY 0.872340 (-6225 1900);
PAINT GREEN (-6225 1900);
DISPLAY INVISIBLE (-6225 1900);
FORCEPROP 2 LAST CDS_LIB standard
J 0
(-6550 2025);
DISPLAY INVISIBLE (-6550 2025);
FORCEADD QUANTA_TITLE_BLOCK_C..1
(0 0);
FORCEPROP 0 LAST CDS_CON_LAST_MODIFIED Fri Mar 11 14:52:15 2022
J 0
(-1885 15);
DISPLAY INVISIBLE (-1885 15);
FORCEPROP 1 LAST CUSTOM_TXT_CDS <CON_LAST_MODIFIED>
J 0
(-1885 15);
DISPLAY 0.978723 (-1885 15);
FORCEPROP 2 LAST CUSTOM_TXT_CDS <XR_PAGE_TITLE>
J 0
(-7890 5250);
DISPLAY 0.638298 (-7890 5250);
PAINT PINK (-7890 5250);
DISPLAY INVISIBLE (-7890 5250);
FORCEPROP 1 LAST CUSTOM_TXT_CDS <NAME_2>
J 0
(-3175 50);
FORCEPROP 1 LAST CUSTOM_TXT_CDS <NAME_1>
J 0
(-3175 175);
FORCEPROP 1 LAST CUSTOM_TXT_CDS <Q_NUMBER>
J 0
(-1403 103);
DISPLAY 1.212766 (-1403 103);
FORCEPROP 1 LAST CUSTOM_TXT_CDS <Q_PROJ>
J 0
(-2382 102);
DISPLAY 1.212766 (-2382 102);
FORCEPROP 1 LAST CUSTOM_TXT_CDS <Q_REV>
J 0
(-184 103);
DISPLAY 1.212766 (-184 103);
FORCEPROP 1 LAST CUSTOM_TXT_CDS <CON_PAGE_NUM> OF <CON_TOTAL_PAGES>
J 0
(-446 18);
DISPLAY 0.978723 (-446 18);
FORCEPROP 1 LAST Q_TITLE CPU0 DDR CHH
J 0
(-9275 50);
DISPLAY 2.446809 (-9275 50);
PAINT GREEN (-9275 50);
FORCEPROP 1 LAST Q_DEPT BU9
J 1
(-3763 49);
DISPLAY 1.957447 (-3763 49);
PAINT GREEN (-3763 49);
FORCEPROP 2 LAST CDS_LIB pure_quanta
J 0
(0 0);
DISPLAY INVISIBLE (0 0);
FORCEPROP 1 LAST CDS_LMAN_SYM_OUTLINE -9475,6775,100,-125
J 0
(0 0);
DISPLAY 0.468085 (0 0);
PAINT GREEN (0 0);
DISPLAY INVISIBLE (0 0);
FORCEPROP 2 LAST PAGE_BORDER TRUE
J 0
(-7890 5250);
DISPLAY 0.638298 (-7890 5250);
PAINT PINK (-7890 5250);
DISPLAY INVISIBLE (-7890 5250);
FORCEPROP 1 LAST COMMENT_BODY TRUE
J 0
(12 -13);
DISPLAY 0.978723 (12 -13);
PAINT GREEN (12 -13);
DISPLAY INVISIBLE (12 -13);
FORCEPROP 2 LAST CDS_XR_PAGE_TITLE CR-17 : @T6G_MB_LIB.T6G(SCH_1):PAGE17
J 0
(-7890 5250);
DISPLAY 0.638298 (-7890 5250);
PAINT PINK (-7890 5250);
DISPLAY INVISIBLE (-7890 5250);
FORCEADD CAD_NOTE..1
(-7700 2425);
FORCEPROP 0 LAST L1 R1947 PLACE CLOSE TO CPU < 25MM
J 0
(-7850 2300);
DISPLAY 0.617021 (-7850 2300);
PAINT WHITE (-7850 2300);
FORCEPROP 2 LAST CDS_LIB pure_quanta_power
J 0
(-7700 2425);
DISPLAY INVISIBLE (-7700 2425);
FORCEPROP 1 LAST COMMENT_BODY TRUE
J 0
(-7675 2525);
DISPLAY 0.574468 (-7675 2525);
PAINT WHITE (-7675 2525);
DISPLAY INVISIBLE (-7675 2525);
WIRE 17 -1 (-3275 5250)(-3275 5200);
WIRE 17 -1 (-3275 5300)(-3275 5250);
WIRE 17 -1 (-3275 5100)(-3275 5200);
WIRE 17 -1 (-3275 5050)(-3275 5100);
WIRE 17 -1 (-3275 5350)(-3275 5300);
WIRE 17 -1 (-3275 5400)(-3275 5350);
WIRE 17 -1 (-3275 5000)(-3275 5050);
WIRE 17 -1 (-3275 4950)(-3275 5000);
WIRE 17 -1 (-3275 5450)(-3275 5400);
WIRE 17 -1 (-3275 5500)(-3275 5450);
WIRE 17 -1 (-3275 4950)(-3275 4900);
WIRE 17 -1 (-3275 4900)(-3275 4850);
WIRE 17 -1 (-3275 5550)(-3275 5500);
WIRE 17 -1 (-3275 5650)(-3275 5550);
WIRE 17 -1 (-3275 4850)(-3275 4800);
WIRE 17 -1 (-3275 4800)(-3275 4750);
WIRE 17 -1 (-3275 5700)(-3275 5650);
WIRE 17 -1 (-3275 5750)(-3275 5700);
WIRE 17 -1 (-3275 4750)(-3275 4650);
WIRE 17 -1 (-3275 4650)(-3275 4600);
WIRE 17 -1 (-3275 5800)(-3275 5750);
WIRE 17 -1 (-3275 5850)(-3275 5800);
WIRE 17 -1 (-3275 4600)(-3275 4550);
WIRE 17 -1 (-3275 4550)(-3275 4500);
WIRE 17 -1 (-3275 5900)(-3275 5850);
WIRE 17 -1 (-3275 5950)(-3275 5900);
WIRE 17 -1 (-3275 4450)(-3275 4500);
WIRE 17 -1 (-3275 4400)(-3275 4450);
WIRE 17 -1 (-3275 6000)(-3275 5950);
WIRE 17 -1 (-3275 6000)(-2650 6000);
FORCEPROP 2 LAST SIG_NAME M_H_CPU0_SA_DQ<31:0>
J 2
(-2710 6010);
DISPLAY 0.489362 (-2710 6010);
WIRE 17 -1 (-3275 4350)(-3275 4400);
WIRE 17 -1 (-3275 4300)(-3275 4350);
WIRE 17 -1 (-3275 4200)(-3275 4150);
WIRE 17 -1 (-3275 4200)(-2650 4200);
FORCEPROP 2 LAST SIG_NAME M_H_CPU0_SB_DQ<31:0>
J 2
(-2710 4210);
DISPLAY 0.489362 (-2710 4210);
WIRE 17 -1 (-3275 3100)(-3275 3050);
WIRE 17 -1 (-3275 3150)(-3275 3100);
WIRE 17 -1 (-3275 3050)(-3275 3000);
WIRE 17 -1 (-3275 3000)(-3275 2950);
WIRE 17 -1 (-3275 3150)(-3275 3200);
WIRE 17 -1 (-3275 3200)(-3275 3250);
WIRE 17 -1 (-3275 2950)(-3275 2850);
WIRE 17 -1 (-3275 2850)(-3275 2800);
WIRE 17 -1 (-3275 3250)(-3275 3300);
WIRE 17 -1 (-3275 3300)(-3275 3400);
WIRE 17 -1 (-3275 2800)(-3275 2750);
WIRE 17 -1 (-3275 2750)(-3275 2700);
WIRE 17 -1 (-3275 3450)(-3275 3400);
WIRE 17 -1 (-3275 3500)(-3275 3450);
WIRE 17 -1 (-3275 2650)(-3275 2700);
WIRE 17 -1 (-3275 2600)(-3275 2650);
WIRE 17 -1 (-3275 3550)(-3275 3500);
WIRE 17 -1 (-3275 3600)(-3275 3550);
WIRE 17 -1 (-3275 2550)(-3275 2600);
WIRE 17 -1 (-3275 2500)(-3275 2550);
WIRE 17 -1 (-3275 3650)(-3275 3600);
WIRE 17 -1 (-3275 3700)(-3275 3650);
WIRE 17 -1 (-3275 3750)(-3275 3700);
WIRE 17 -1 (-3275 3850)(-3275 3750);
WIRE 17 -1 (-3275 3900)(-3275 3850);
WIRE 17 -1 (-3275 3950)(-3275 3900);
WIRE 17 -1 (-3275 4000)(-3275 3950);
WIRE 17 -1 (-3275 4050)(-3275 4000);
WIRE 17 -1 (-3275 4100)(-3275 4050);
WIRE 17 -1 (-3275 4150)(-3275 4100);
WIRE 17 -1 (-3275 2100)(-3275 2150);
WIRE 17 -1 (-3275 2050)(-3275 2100);
WIRE 17 -1 (-3275 2150)(-3275 2200);
WIRE 17 -1 (-3275 2200)(-3275 2250);
WIRE 17 -1 (-3275 2300)(-3275 2250);
WIRE 17 -1 (-3275 2300)(-3275 2350);
WIRE 17 -1 (-3275 2400)(-3275 2350);
WIRE 17 -1 (-3275 2400)(-3275 2425);
WIRE 17 -1 (-3275 2425)(-2775 2425);
FORCEPROP 2 LAST SIG_NAME M_H_CPU0_SA_CB<7:0>
J 2
(-2775 2435);
DISPLAY 0.489362 (-2775 2435);
WIRE 17 -1 (-3275 1950)(-3275 1900);
WIRE 17 -1 (-3275 1950)(-3275 1975);
WIRE 17 -1 (-3275 1850)(-3275 1900);
WIRE 17 -1 (-3275 1850)(-3275 1800);
WIRE 17 -1 (-3275 1975)(-2775 1975);
FORCEPROP 2 LAST SIG_NAME M_H_CPU0_SB_CB<7:0>
J 2
(-2775 1985);
DISPLAY 0.489362 (-2775 1985);
WIRE 17 -1 (-3275 1750)(-3275 1800);
WIRE 17 -1 (-3275 1700)(-3275 1750);
WIRE 17 -1 (-3275 1650)(-3275 1700);
WIRE 17 -1 (-3275 1600)(-3275 1650);
WIRE 17 -1 (-6000 5750)(-6000 5650);
WIRE 17 -1 (-6000 5850)(-6000 5750);
WIRE 17 -1 (-6000 5650)(-6000 5550);
WIRE 17 -1 (-6000 5450)(-6000 5550);
WIRE 17 -1 (-6000 5950)(-6000 5850);
FORCEPROP 2 LAST SIG_NAME M_H_CPU0_SA_DQS_DN<9:0>
J 2
(-6035 5960);
DISPLAY 0.489362 (-6035 5960);
WIRE 17 -1 (-6000 5350)(-6000 5450);
WIRE 17 -1 (-6000 5250)(-6000 5350);
WIRE 17 -1 (-6000 5250)(-6000 5150);
WIRE 17 -1 (-5800 6000)(-5800 5900);
WIRE 17 -1 (-5800 6000)(-6600 6000);
FORCEPROP 2 LAST SIG_NAME M_H_CPU0_SA_DQS_DP<9:0>
J 2
(-6035 6010);
DISPLAY 0.489362 (-6035 6010);
WIRE 17 -1 (-6000 5150)(-6000 5050);
WIRE 17 -1 (-5800 5900)(-5800 5800);
WIRE 17 -1 (-5800 5800)(-5800 5700);
WIRE 17 -1 (-5800 5700)(-5800 5600);
WIRE 17 -1 (-5800 5500)(-5800 5600);
WIRE 17 -1 (-5800 5400)(-5800 5500);
WIRE 17 -1 (-5800 5300)(-5800 5400);
WIRE 17 -1 (-5800 5300)(-5800 5200);
WIRE 17 -1 (-5800 5200)(-5800 5100);
WIRE 17 -1 (-6000 4900)(-6000 4800);
FORCEPROP 2 LAST SIG_NAME M_H_CPU0_SB_DQS_DN<9:0>
J 2
(-6035 4910);
DISPLAY 0.489362 (-6035 4910);
WIRE 17 -1 (-6000 4700)(-6000 4600);
WIRE 17 -1 (-6000 4800)(-6000 4700);
WIRE 17 -1 (-6000 4600)(-6000 4500);
WIRE 17 -1 (-6000 4400)(-6000 4500);
WIRE 17 -1 (-6000 4300)(-6000 4400);
WIRE 17 -1 (-6000 4200)(-6000 4300);
WIRE 17 -1 (-6000 4200)(-6000 4100);
WIRE 17 -1 (-5800 4950)(-5800 4850);
WIRE 17 -1 (-5800 4950)(-6600 4950);
FORCEPROP 2 LAST SIG_NAME M_H_CPU0_SB_DQS_DP<9:0>
J 2
(-6035 4960);
DISPLAY 0.489362 (-6035 4960);
WIRE 17 -1 (-6000 4100)(-6000 4000);
WIRE 17 -1 (-5800 4850)(-5800 4750);
WIRE 17 -1 (-5800 4750)(-5800 4650);
WIRE 17 -1 (-5800 4650)(-5800 4550);
WIRE 17 -1 (-5800 4450)(-5800 4550);
WIRE 17 -1 (-5800 4350)(-5800 4450);
WIRE 17 -1 (-5800 4250)(-5800 4350);
WIRE 17 -1 (-5800 4250)(-5800 4150);
WIRE 17 -1 (-5800 4150)(-5800 4050);
WIRE 17 -1 (-6000 3800)(-6000 3850);
WIRE 17 -1 (-6000 3750)(-6000 3800);
WIRE 17 -1 (-6000 3850)(-6500 3850);
FORCEPROP 2 LAST SIG_NAME M_H_CPU0_SA_CA<6:0>
J 0
(-6500 3860);
DISPLAY 0.489362 (-6500 3860);
WIRE 17 -1 (-6000 3400)(-6000 3450);
WIRE 17 -1 (-6000 3350)(-6000 3400);
WIRE 17 -1 (-6000 3450)(-6500 3450);
FORCEPROP 2 LAST SIG_NAME M_H_CPU0_SB_CA<6:0>
J 0
(-6500 3460);
DISPLAY 0.489362 (-6500 3460);
WIRE 17 -1 (-6000 3700)(-6000 3750);
WIRE 17 -1 (-6000 3300)(-6000 3350);
WIRE 17 -1 (-6000 3650)(-6000 3700);
WIRE 17 -1 (-6000 3600)(-6000 3650);
WIRE 17 -1 (-6000 3550)(-6000 3600);
WIRE 17 -1 (-6000 3250)(-6000 3300);
WIRE 17 -1 (-6000 3200)(-6000 3250);
WIRE 17 -1 (-6000 3150)(-6000 3200);
WIRE 17 -1 (-6000 5950)(-6600 5950);
WIRE 17 -1 (-6000 4900)(-6600 4900);
WIRE 16 -1 (-7700 2125)(-6975 2125);
FORCEPROP 2 LAST SIG_NAME M_H_CPU0_ALERT_N
J 0
(-7660 2135);
DISPLAY 0.489362 (-7660 2135);
WIRE 16 -1 (-6500 1175)(-5400 1175);
FORCEPROP 2 LAST SIG_NAME TP_M_H_CPU0_SA_TEST39H
J 0
(-6485 1185);
DISPLAY 0.489362 (-6485 1185);
FORCEPROP 2 LASTPROP $XRERR UNIQUE?
J 0
(-6740 1175);
DISPLAY 0.638298 (-6740 1175);
PAINT MONO (-6740 1175);
DISPLAY INVISIBLE (-6740 1175);
WIRE 16 -1 (-6775 2125)(-5400 2125);
FORCEPROP 2 LAST SIG_NAME M_H_CPU0_ALERT_R_N
J 0
(-6485 2135);
DISPLAY 0.489362 (-6485 2135);
FORCEPROP 2 LASTPROP $XRERR UNIQUE?
J 0
(-6725 2135);
DISPLAY 0.638298 (-6725 2135);
PAINT MONO (-6725 2135);
DISPLAY INVISIBLE (-6725 2135);
WIRE 16 -1 (-6500 2975)(-5400 2975);
FORCEPROP 2 LAST SIG_NAME M_H_CPU0_CLK_DP<0>
J 0
(-6500 2985);
DISPLAY 0.489362 (-6500 2985);
WIRE 16 -1 (-6500 2925)(-5400 2925);
FORCEPROP 2 LAST SIG_NAME M_H_CPU0_CLK_DN<0>
J 0
(-6500 2935);
DISPLAY 0.489362 (-6500 2935);
WIRE 16 -1 (-6500 2825)(-5400 2825);
FORCEPROP 2 LAST SIG_NAME M_H_CPU0_SA_CS_N<0>
J 0
(-6500 2835);
DISPLAY 0.489362 (-6500 2835);
WIRE 16 -1 (-6500 2775)(-5400 2775);
FORCEPROP 2 LAST SIG_NAME M_H_CPU0_SA_CS_N<1>
J 0
(-6500 2785);
DISPLAY 0.489362 (-6500 2785);
WIRE 16 -1 (-6500 2675)(-5400 2675);
FORCEPROP 2 LAST SIG_NAME M_H_CPU0_SA_RSP<0>
J 0
(-6500 2685);
DISPLAY 0.489362 (-6500 2685);
WIRE 16 -1 (-6500 2575)(-5400 2575);
FORCEPROP 2 LAST SIG_NAME M_H_CPU0_SA_PAR
J 0
(-6500 2585);
DISPLAY 0.489362 (-6500 2585);
WIRE 16 -1 (-6500 2425)(-5400 2425);
FORCEPROP 2 LAST SIG_NAME M_H_CPU0_SB_CS_N<1>
J 0
(-6500 2435);
DISPLAY 0.489362 (-6500 2435);
WIRE 16 -1 (-6500 2475)(-5400 2475);
FORCEPROP 2 LAST SIG_NAME M_H_CPU0_SB_CS_N<0>
J 0
(-6500 2485);
DISPLAY 0.489362 (-6500 2485);
WIRE 16 -1 (-6500 2325)(-5400 2325);
FORCEPROP 2 LAST SIG_NAME M_H_CPU0_SB_RSP<0>
J 0
(-6500 2335);
DISPLAY 0.489362 (-6500 2335);
WIRE 16 -1 (-6500 2225)(-5400 2225);
FORCEPROP 2 LAST SIG_NAME M_H_CPU0_SB_PAR
J 0
(-6500 2235);
DISPLAY 0.489362 (-6500 2235);
WIRE 16 -1 (-6500 2025)(-5400 2025);
FORCEPROP 2 LAST SIG_NAME M_H_CPU0_RESET_N
J 0
(-6500 2035);
DISPLAY 0.489362 (-6500 2035);
WIRE 16 -1 (-5700 4025)(-5400 4025);
WIRE 16 -1 (-5900 3975)(-5400 3975);
WIRE 16 -1 (-5900 4075)(-5400 4075);
WIRE 16 -1 (-5900 3125)(-5400 3125);
WIRE 16 -1 (-5900 3525)(-5400 3525);
WIRE 16 -1 (-5900 3175)(-5400 3175);
WIRE 16 -1 (-5900 3575)(-5400 3575);
WIRE 16 -1 (-5900 3225)(-5400 3225);
WIRE 16 -1 (-5900 3625)(-5400 3625);
WIRE 16 -1 (-5900 3275)(-5400 3275);
WIRE 16 -1 (-5900 3675)(-5400 3675);
WIRE 16 -1 (-5900 3325)(-5400 3325);
WIRE 16 -1 (-5900 3725)(-5400 3725);
WIRE 16 -1 (-5900 3375)(-5400 3375);
WIRE 16 -1 (-5900 3775)(-5400 3775);
WIRE 16 -1 (-5900 3425)(-5400 3425);
WIRE 16 -1 (-5900 3825)(-5400 3825);
WIRE 16 -1 (-5700 4125)(-5400 4125);
WIRE 16 -1 (-5700 4225)(-5400 4225);
WIRE 16 -1 (-5700 4325)(-5400 4325);
WIRE 16 -1 (-5700 4425)(-5400 4425);
WIRE 16 -1 (-5700 4525)(-5400 4525);
WIRE 16 -1 (-5700 5075)(-5400 5075);
WIRE 16 -1 (-5700 4625)(-5400 4625);
WIRE 16 -1 (-5900 4175)(-5400 4175);
WIRE 16 -1 (-5700 4725)(-5400 4725);
WIRE 16 -1 (-5900 4275)(-5400 4275);
WIRE 16 -1 (-5700 4825)(-5400 4825);
WIRE 16 -1 (-5900 4375)(-5400 4375);
WIRE 16 -1 (-5700 4925)(-5400 4925);
WIRE 16 -1 (-5900 4475)(-5400 4475);
WIRE 16 -1 (-5900 5025)(-5400 5025);
WIRE 16 -1 (-5900 4575)(-5400 4575);
WIRE 16 -1 (-5900 4675)(-5400 4675);
WIRE 16 -1 (-5900 4775)(-5400 4775);
WIRE 16 -1 (-5900 4875)(-5400 4875);
WIRE 16 -1 (-5900 5825)(-5400 5825);
WIRE 16 -1 (-5900 5925)(-5400 5925);
WIRE 16 -1 (-5700 5175)(-5400 5175);
WIRE 16 -1 (-5700 5275)(-5400 5275);
WIRE 16 -1 (-5700 5375)(-5400 5375);
WIRE 16 -1 (-5700 5475)(-5400 5475);
WIRE 16 -1 (-5700 5575)(-5400 5575);
WIRE 16 -1 (-5900 5125)(-5400 5125);
WIRE 16 -1 (-5700 5675)(-5400 5675);
WIRE 16 -1 (-5900 5225)(-5400 5225);
WIRE 16 -1 (-5700 5775)(-5400 5775);
WIRE 16 -1 (-5900 5325)(-5400 5325);
WIRE 16 -1 (-5700 5875)(-5400 5875);
WIRE 16 -1 (-5900 5425)(-5400 5425);
WIRE 16 -1 (-5700 5975)(-5400 5975);
WIRE 16 -1 (-5900 5525)(-5400 5525);
WIRE 16 -1 (-5900 5625)(-5400 5625);
WIRE 16 -1 (-5900 5725)(-5400 5725);
WIRE 16 -1 (-3800 1575)(-3375 1575);
WIRE 16 -1 (-3800 1625)(-3375 1625);
WIRE 16 -1 (-3800 1675)(-3375 1675);
WIRE 16 -1 (-3800 1725)(-3375 1725);
WIRE 16 -1 (-3800 1775)(-3375 1775);
WIRE 16 -1 (-3800 1825)(-3375 1825);
WIRE 16 -1 (-3800 2025)(-3375 2025);
WIRE 16 -1 (-3800 1875)(-3375 1875);
WIRE 16 -1 (-3800 1925)(-3375 1925);
WIRE 16 -1 (-3800 2125)(-3375 2125);
WIRE 16 -1 (-3800 2525)(-3375 2525);
WIRE 16 -1 (-3800 2175)(-3375 2175);
WIRE 16 -1 (-3800 2225)(-3375 2225);
WIRE 16 -1 (-3800 2275)(-3375 2275);
WIRE 16 -1 (-3800 2325)(-3375 2325);
WIRE 16 -1 (-3800 2375)(-3375 2375);
WIRE 16 -1 (-3800 2575)(-3375 2575);
WIRE 16 -1 (-3800 2625)(-3375 2625);
WIRE 16 -1 (-3800 2675)(-3375 2675);
WIRE 16 -1 (-3800 2725)(-3375 2725);
WIRE 16 -1 (-3800 2775)(-3375 2775);
WIRE 16 -1 (-3800 2825)(-3375 2825);
WIRE 16 -1 (-3800 2925)(-3375 2925);
WIRE 16 -1 (-3800 2975)(-3375 2975);
WIRE 16 -1 (-3800 3025)(-3375 3025);
WIRE 16 -1 (-3800 2075)(-3375 2075);
WIRE 16 -1 (-3800 2475)(-3375 2475);
WIRE 16 -1 (-3800 3675)(-3375 3675);
WIRE 16 -1 (-3800 3725)(-3375 3725);
WIRE 16 -1 (-3800 3825)(-3375 3825);
WIRE 16 -1 (-3800 3875)(-3375 3875);
WIRE 16 -1 (-3800 3925)(-3375 3925);
WIRE 16 -1 (-3800 3125)(-3375 3125);
WIRE 16 -1 (-3800 3975)(-3375 3975);
WIRE 16 -1 (-3800 3175)(-3375 3175);
WIRE 16 -1 (-3800 4025)(-3375 4025);
WIRE 16 -1 (-3800 3225)(-3375 3225);
WIRE 16 -1 (-3800 4075)(-3375 4075);
WIRE 16 -1 (-3800 3275)(-3375 3275);
WIRE 16 -1 (-3800 3375)(-3375 3375);
WIRE 16 -1 (-3800 3425)(-3375 3425);
WIRE 16 -1 (-3800 3475)(-3375 3475);
WIRE 16 -1 (-3800 3525)(-3375 3525);
WIRE 16 -1 (-3800 3575)(-3375 3575);
WIRE 16 -1 (-3800 3625)(-3375 3625);
WIRE 16 -1 (-3800 3075)(-3375 3075);
WIRE 16 -1 (-3800 4575)(-3375 4575);
WIRE 16 -1 (-3800 4625)(-3375 4625);
WIRE 16 -1 (-3800 4725)(-3375 4725);
WIRE 16 -1 (-3800 4775)(-3375 4775);
WIRE 16 -1 (-3800 4825)(-3375 4825);
WIRE 16 -1 (-3800 4875)(-3375 4875);
WIRE 16 -1 (-3800 4275)(-3375 4275);
WIRE 16 -1 (-3800 4325)(-3375 4325);
WIRE 16 -1 (-3800 4125)(-3375 4125);
WIRE 16 -1 (-3800 4175)(-3375 4175);
WIRE 16 -1 (-3800 4925)(-3375 4925);
WIRE 16 -1 (-3800 4975)(-3375 4975);
WIRE 16 -1 (-3800 4375)(-3375 4375);
WIRE 16 -1 (-3800 5025)(-3375 5025);
WIRE 16 -1 (-3800 4425)(-3375 4425);
WIRE 16 -1 (-3800 5075)(-3375 5075);
WIRE 16 -1 (-3800 4475)(-3375 4475);
WIRE 16 -1 (-3800 4525)(-3375 4525);
WIRE 16 -1 (-3800 5225)(-3375 5225);
WIRE 16 -1 (-3800 5275)(-3375 5275);
WIRE 16 -1 (-3800 5475)(-3375 5475);
WIRE 16 -1 (-3800 5325)(-3375 5325);
WIRE 16 -1 (-3800 5525)(-3375 5525);
WIRE 16 -1 (-3800 5375)(-3375 5375);
WIRE 16 -1 (-3800 5625)(-3375 5625);
WIRE 16 -1 (-3800 5425)(-3375 5425);
WIRE 16 -1 (-3800 5675)(-3375 5675);
WIRE 16 -1 (-3800 5725)(-3375 5725);
WIRE 16 -1 (-3800 5775)(-3375 5775);
WIRE 16 -1 (-3800 5825)(-3375 5825);
WIRE 16 -1 (-3800 5875)(-3375 5875);
WIRE 16 -1 (-3800 5925)(-3375 5925);
WIRE 16 -1 (-3800 5975)(-3375 5975);
WIRE 16 -1 (-3800 5175)(-3375 5175);
QUIT
